FILE_TYPE = MACRO_DRAWING;
SET COLOR_WIRE YELLOW;
SET COLOR_PROP MONO;
SET COLOR_DOT WHITE;
SET COLOR_ARC YELLOW;
SET COLOR_BODY GREEN;
SET COLOR_NOTE MONO;
SET PROP_DISPLAY VALUE;
SET PAGE_NUMBER P113;
FORCEADD NC7SB3157..1
R 2
(-2075 3525);
FORCEPROP 2 LASTPIN (-1725 3375) $PN 5
J 0
(-1715 3385);
DISPLAY 0.617021 (-1715 3385);
PAINT ORANGE (-1715 3385);
FORCEPROP 2 LASTPIN (-2425 3525) $PN 4
J 2
(-2435 3535);
DISPLAY 0.617021 (-2435 3535);
PAINT ORANGE (-2435 3535);
FORCEPROP 2 LASTPIN (-2425 3375) $PN 2
J 2
(-2435 3385);
DISPLAY 0.617021 (-2435 3385);
PAINT ORANGE (-2435 3385);
FORCEPROP 1 LAST PACK_TYPE SMLF
J 2
(-1900 3275);
DISPLAY 0.617021 (-1900 3275);
PAINT SKYBLUE (-1900 3275);
FORCEPROP 2 LASTPIN (-1725 3575) $PN 3
J 0
(-1715 3585);
DISPLAY 0.617021 (-1715 3585);
PAINT ORANGE (-1715 3585);
FORCEPROP 1 LAST PART_NUMBER C99406-001
J 2
(-1775 3750);
DISPLAY 0.617021 (-1775 3750);
PAINT BLUE (-1775 3750);
FORCEPROP 2 LASTPIN (-1725 3475) $PN 1
J 0
(-1715 3485);
DISPLAY 0.617021 (-1715 3485);
PAINT ORANGE (-1715 3485);
FORCEPROP 1 LAST MATERIAL IC
J 2
(-1775 3275);
DISPLAY 0.617021 (-1775 3275);
PAINT SKYBLUE (-1775 3275);
FORCEPROP 2 LASTPIN (-1725 3675) $PN 6
J 0
(-1715 3685);
DISPLAY 0.617021 (-1715 3685);
PAINT ORANGE (-1715 3685);
FORCEPROP 1 LAST LOCATION U1M2
J 2
(-1775 3800);
DISPLAY 0.617021 (-1775 3800);
PAINT AQUA (-1775 3800);
FORCEPROP 0 LAST GROUP MCP
J 0
(-2375 3225);
DISPLAY 0.638298 (-2375 3225);
PAINT BROWN (-2375 3225);
DISPLAY BOTH (-2375 3225);
FORCEPROP 1 LAST PATH I107
J 2
(-2150 3275);
DISPLAY 0.851064 (-2150 3275);
PAINT WHITE (-2150 3275);
DISPLAY INVISIBLE (-2150 3275);
FORCEPROP 2 LAST CDS_LIB mstr_analog
J 0
(-2075 3525);
PAINT MONO (-2075 3525);
DISPLAY INVISIBLE (-2075 3525);
FORCEPROP 2 LAST ROOM DEBUG
J 0
(-1775 3850);
DISPLAY 1.617021 (-1775 3850);
PAINT WHITE (-1775 3850);
DISPLAY INVISIBLE (-1775 3850);
FORCEPROP 2 LAST SEC 1
J 0
(-1775 3850);
DISPLAY 0.680851 (-1775 3850);
PAINT MONO (-1775 3850);
DISPLAY INVISIBLE (-1775 3850);
FORCEPROP 2 LAST SEC_TYPE SMLF
J 0
(-1775 3850);
DISPLAY 1.021277 (-1775 3850);
PAINT ORANGE (-1775 3850);
DISPLAY INVISIBLE (-1775 3850);
FORCEPROP 2 LAST BOM_COST DEBUG
J 0
(-1775 3900);
DISPLAY 1.617021 (-1775 3900);
PAINT WHITE (-1775 3900);
DISPLAY INVISIBLE (-1775 3900);
FORCEADD GND..1
(-2500 3225);
FORCEPROP 3 LASTPIN (-2500 3275) SIG_NAME GND\g
J 0
(-2490 3285);
DISPLAY 0.659574 (-2490 3285);
PAINT MONO (-2490 3285);
DISPLAY INVISIBLE (-2490 3285);
FORCEPROP 1 LAST HDL_POWER GND
J 0
(-2500 3375);
DISPLAY 0.872340 (-2500 3375);
PAINT GREEN (-2500 3375);
DISPLAY INVISIBLE (-2500 3375);
FORCEPROP 1 LAST BODY_TYPE PLUMBING
J 0
(-2545 3182);
DISPLAY 0.340426 (-2545 3182);
PAINT GREEN (-2545 3182);
DISPLAY INVISIBLE (-2545 3182);
FORCEPROP 2 LAST CDS_LIB mstr_symbols
J 0
(-2500 3225);
PAINT MONO (-2500 3225);
DISPLAY INVISIBLE (-2500 3225);
FORCEPROP 1 LAST VOLTAGE 0.0V
J 0
(-2545 3182);
DISPLAY 0.340426 (-2545 3182);
PAINT SKYBLUE (-2545 3182);
DISPLAY INVISIBLE (-2545 3182);
FORCEPROP 1 LAST PATH I109
J 0
(-2425 3225);
DISPLAY 0.872340 (-2425 3225);
PAINT AQUA (-2425 3225);
DISPLAY INVISIBLE (-2425 3225);
FORCEPROP 1 LAST SIZE 1B
J 0
(-2425 3175);
DISPLAY 0.872340 (-2425 3175);
PAINT AQUA (-2425 3175);
DISPLAY INVISIBLE (-2425 3175);
FORCEADD GND..1
(-1150 4200);
FORCEPROP 3 LASTPIN (-1150 4250) SIG_NAME GND\g
J 0
(-1140 4260);
DISPLAY 0.659574 (-1140 4260);
PAINT MONO (-1140 4260);
DISPLAY INVISIBLE (-1140 4260);
FORCEPROP 1 LAST HDL_POWER GND
J 0
(-1150 4350);
DISPLAY 0.872340 (-1150 4350);
PAINT GREEN (-1150 4350);
DISPLAY INVISIBLE (-1150 4350);
FORCEPROP 1 LAST BODY_TYPE PLUMBING
J 0
(-1195 4157);
DISPLAY 0.340426 (-1195 4157);
PAINT GREEN (-1195 4157);
DISPLAY INVISIBLE (-1195 4157);
FORCEPROP 1 LAST SIZE 1B
J 0
(-1075 4150);
DISPLAY 0.872340 (-1075 4150);
PAINT AQUA (-1075 4150);
DISPLAY INVISIBLE (-1075 4150);
FORCEPROP 1 LAST VOLTAGE 0.0V
J 0
(-1195 4157);
DISPLAY 0.340426 (-1195 4157);
PAINT SKYBLUE (-1195 4157);
DISPLAY INVISIBLE (-1195 4157);
FORCEPROP 2 LAST CDS_LIB mstr_symbols
J 0
(-1150 4200);
PAINT MONO (-1150 4200);
DISPLAY INVISIBLE (-1150 4200);
FORCEPROP 1 LAST PATH I110
J 0
(-1075 4200);
DISPLAY 0.872340 (-1075 4200);
PAINT AQUA (-1075 4200);
DISPLAY INVISIBLE (-1075 4200);
FORCEADD OFFPAGE..4
(-1050 3675);
FORCEPROP 2 LAST $XR0 191 
J 0
(-864 3675);
DISPLAY 0.638298 (-864 3675);
PAINT MONO (-864 3675);
DISPLAY INVISIBLE (-864 3675);
FORCEPROP 1 LAST COMMENT_BODY TRUE
J 0
(-1075 3575);
DISPLAY 0.872340 (-1075 3575);
PAINT GREEN (-1075 3575);
DISPLAY INVISIBLE (-1075 3575);
FORCEPROP 1 LAST OFFPAGE TRUE
J 0
(-725 3550);
DISPLAY 0.872340 (-725 3550);
PAINT GREEN (-725 3550);
DISPLAY INVISIBLE (-725 3550);
FORCEPROP 2 LAST CDS_LIB mstr_standard
J 0
(-1050 3675);
PAINT MONO (-1050 3675);
DISPLAY INVISIBLE (-1050 3675);
FORCEPROP 2 LAST PATH I111
J 0
(-875 3750);
DISPLAY 1.021277 (-875 3750);
PAINT ORANGE (-875 3750);
DISPLAY INVISIBLE (-875 3750);
FORCEADD OFFPAGE..2
(-600 850);
FORCEPROP 2 LAST $XR0 113 
J 0
(-411 850);
DISPLAY 0.638298 (-411 850);
PAINT MONO (-411 850);
FORCEPROP 2 LAST $XR1 63 
J 0
(-291 850);
DISPLAY 0.638298 (-291 850);
PAINT MONO (-291 850);
FORCEPROP 1 LAST COMMENT_BODY TRUE
J 0
(-645 755);
DISPLAY 0.872340 (-645 755);
PAINT GREEN (-645 755);
DISPLAY INVISIBLE (-645 755);
FORCEPROP 1 LAST OFFPAGE TRUE
J 0
(-275 725);
DISPLAY 0.872340 (-275 725);
PAINT GREEN (-275 725);
DISPLAY INVISIBLE (-275 725);
FORCEPROP 2 LAST PATH I112
J 0
(-425 925);
DISPLAY 1.021277 (-425 925);
PAINT ORANGE (-425 925);
DISPLAY INVISIBLE (-425 925);
FORCEPROP 2 LAST CDS_LIB mstr_standard
J 0
(-600 850);
PAINT MONO (-600 850);
DISPLAY INVISIBLE (-600 850);
FORCEADD OFFPAGE..1
(-2475 800);
FORCEPROP 2 LAST $XR0 191 
J 0
(-2757 800);
DISPLAY 0.638298 (-2757 800);
PAINT MONO (-2757 800);
FORCEPROP 1 LAST COMMENT_BODY TRUE
J 0
(-2350 700);
DISPLAY 0.872340 (-2350 700);
PAINT GREEN (-2350 700);
DISPLAY INVISIBLE (-2350 700);
FORCEPROP 1 LAST OFFPAGE TRUE
J 0
(-2150 675);
DISPLAY 0.872340 (-2150 675);
PAINT GREEN (-2150 675);
DISPLAY INVISIBLE (-2150 675);
FORCEPROP 2 LAST CDS_LIB mstr_standard
J 0
(-2475 800);
PAINT MONO (-2475 800);
DISPLAY INVISIBLE (-2475 800);
FORCEPROP 2 LAST PATH I113
J 0
(-2300 875);
DISPLAY 1.021277 (-2300 875);
PAINT ORANGE (-2300 875);
DISPLAY INVISIBLE (-2300 875);
FORCEADD CAP_A..1
R 2
(-1550 3025);
FORCEPROP 1 LAST LOCATION C1M31
J 2
(-1600 3125);
DISPLAY 0.617021 (-1600 3125);
PAINT AQUA (-1600 3125);
FORCEPROP 1 LAST VALUE 0.01UF
J 2
(-1600 3075);
DISPLAY 0.617021 (-1600 3075);
PAINT SKYBLUE (-1600 3075);
FORCEPROP 1 LAST VOLTAGE 25V
J 2
(-1600 3025);
DISPLAY 0.617021 (-1600 3025);
PAINT SKYBLUE (-1600 3025);
FORCEPROP 1 LAST TOLERANCE 10%
J 2
(-1600 2975);
DISPLAY 0.617021 (-1600 2975);
PAINT SKYBLUE (-1600 2975);
FORCEPROP 1 LAST MATERIAL X7R
J 2
(-1600 2925);
DISPLAY 0.617021 (-1600 2925);
PAINT SKYBLUE (-1600 2925);
FORCEPROP 1 LASTPIN (-1550 2925) $PN 2
J 2
(-1560 2905);
DISPLAY 0.617021 (-1560 2905);
PAINT ORANGE (-1560 2905);
FORCEPROP 1 LASTPIN (-1550 3125) $PN 1
J 2
(-1560 3105);
DISPLAY 0.617021 (-1560 3105);
PAINT ORANGE (-1560 3105);
FORCEPROP 0 LAST GROUP MCP
J 0
(-1800 2775);
DISPLAY 0.638298 (-1800 2775);
PAINT BROWN (-1800 2775);
DISPLAY BOTH (-1800 2775);
FORCEPROP 1 LAST PACK_TYPE 0402V
J 2
(-1600 2825);
DISPLAY 0.617021 (-1600 2825);
PAINT SKYBLUE (-1600 2825);
FORCEPROP 1 LAST PART_NUMBER A36096-045
J 2
(-1600 2875);
DISPLAY 0.617021 (-1600 2875);
PAINT BLUE (-1600 2875);
FORCEPROP 2 LAST CDS_LIB dev_discrete
J 0
(-1550 3025);
PAINT ORANGE (-1550 3025);
DISPLAY INVISIBLE (-1550 3025);
FORCEPROP 2 LAST CDS_SEC 1
J 0
(-1600 3175);
PAINT ORANGE (-1600 3175);
DISPLAY INVISIBLE (-1600 3175);
FORCEPROP 2 LAST BOM_COST DEBUG
J 0
(-1600 3175);
DISPLAY 1.617021 (-1600 3175);
PAINT WHITE (-1600 3175);
DISPLAY INVISIBLE (-1600 3175);
FORCEPROP 1 LAST PATH I116
J 2
(-1600 3175);
DISPLAY 0.978723 (-1600 3175);
PAINT WHITE (-1600 3175);
DISPLAY INVISIBLE (-1600 3175);
FORCEPROP 2 LAST ROOM DEBUG
J 2
(-1600 3175);
DISPLAY 1.617021 (-1600 3175);
PAINT WHITE (-1600 3175);
DISPLAY INVISIBLE (-1600 3175);
FORCEPROP 2 LAST SEC 1
J 0
(-1600 3225);
DISPLAY 0.680851 (-1600 3225);
PAINT MONO (-1600 3225);
DISPLAY INVISIBLE (-1600 3225);
FORCEPROP 2 LAST SEC_TYPE 0402V
J 0
(-1600 3225);
DISPLAY 1.021277 (-1600 3225);
PAINT ORANGE (-1600 3225);
DISPLAY INVISIBLE (-1600 3225);
FORCEADD CAP_A..1
R 2
(-1250 3025);
FORCEPROP 1 LAST PACK_TYPE 0402V
J 2
(-1300 2825);
DISPLAY 0.617021 (-1300 2825);
PAINT SKYBLUE (-1300 2825);
FORCEPROP 1 LAST VALUE 1.0UF
J 2
(-1300 3075);
DISPLAY 0.617021 (-1300 3075);
PAINT SKYBLUE (-1300 3075);
FORCEPROP 0 LAST GROUP MCP
J 0
(-1500 2750);
DISPLAY 0.638298 (-1500 2750);
PAINT BROWN (-1500 2750);
DISPLAY BOTH (-1500 2750);
FORCEPROP 1 LAST VOLTAGE 6.3V
J 2
(-1300 3025);
DISPLAY 0.617021 (-1300 3025);
PAINT SKYBLUE (-1300 3025);
FORCEPROP 1 LAST LOCATION C1M32
J 2
(-1300 3125);
DISPLAY 0.617021 (-1300 3125);
PAINT AQUA (-1300 3125);
FORCEPROP 1 LASTPIN (-1250 3125) $PN 1
J 2
(-1260 3105);
DISPLAY 0.617021 (-1260 3105);
PAINT ORANGE (-1260 3105);
FORCEPROP 1 LAST TOLERANCE 10%
J 2
(-1300 2975);
DISPLAY 0.617021 (-1300 2975);
PAINT SKYBLUE (-1300 2975);
FORCEPROP 1 LAST MATERIAL X6S
J 2
(-1300 2925);
DISPLAY 0.617021 (-1300 2925);
PAINT SKYBLUE (-1300 2925);
FORCEPROP 1 LAST PART_NUMBER D97712-004
J 2
(-1300 2875);
DISPLAY 0.617021 (-1300 2875);
PAINT BLUE (-1300 2875);
FORCEPROP 1 LASTPIN (-1250 2925) $PN 2
J 2
(-1260 2905);
DISPLAY 0.617021 (-1260 2905);
PAINT ORANGE (-1260 2905);
FORCEPROP 2 LAST CDS_LIB dev_discrete
J 0
(-1250 3025);
PAINT ORANGE (-1250 3025);
DISPLAY INVISIBLE (-1250 3025);
FORCEPROP 2 LAST ROOM DEBUG
J 2
(-1300 3175);
DISPLAY 1.617021 (-1300 3175);
PAINT WHITE (-1300 3175);
DISPLAY INVISIBLE (-1300 3175);
FORCEPROP 1 LAST PATH I117
J 2
(-1300 3175);
DISPLAY 0.978723 (-1300 3175);
PAINT WHITE (-1300 3175);
DISPLAY INVISIBLE (-1300 3175);
FORCEPROP 2 LAST SEC 1
J 0
(-1300 3225);
DISPLAY 0.680851 (-1300 3225);
PAINT MONO (-1300 3225);
DISPLAY INVISIBLE (-1300 3225);
FORCEPROP 2 LAST SEC_TYPE 0402V
J 0
(-1300 3225);
DISPLAY 1.021277 (-1300 3225);
PAINT ORANGE (-1300 3225);
DISPLAY INVISIBLE (-1300 3225);
FORCEPROP 2 LAST CDS_SEC 1
J 0
(-1300 3175);
PAINT ORANGE (-1300 3175);
DISPLAY INVISIBLE (-1300 3175);
FORCEPROP 2 LAST BOM_COST DEBUG
J 0
(-1300 3175);
DISPLAY 1.617021 (-1300 3175);
PAINT WHITE (-1300 3175);
DISPLAY INVISIBLE (-1300 3175);
FORCEADD GND..1
(-1250 2725);
FORCEPROP 3 LASTPIN (-1250 2775) SIG_NAME GND\g
J 0
(-1240 2785);
DISPLAY 0.659574 (-1240 2785);
PAINT MONO (-1240 2785);
DISPLAY INVISIBLE (-1240 2785);
FORCEPROP 1 LAST HDL_POWER GND
J 0
(-1250 2875);
PAINT GREEN (-1250 2875);
DISPLAY INVISIBLE (-1250 2875);
FORCEPROP 1 LAST BODY_TYPE PLUMBING
J 0
(-1295 2682);
DISPLAY 0.340426 (-1295 2682);
PAINT GREEN (-1295 2682);
DISPLAY INVISIBLE (-1295 2682);
FORCEPROP 2 LAST BOM_COST DEBUG
J 0
(-1725 2850);
DISPLAY 1.617021 (-1725 2850);
PAINT WHITE (-1725 2850);
DISPLAY INVISIBLE (-1725 2850);
FORCEPROP 2 LAST ROOM DEBUG
J 0
(-1725 2800);
DISPLAY 1.617021 (-1725 2800);
PAINT WHITE (-1725 2800);
DISPLAY INVISIBLE (-1725 2800);
FORCEPROP 1 LAST VOLTAGE 0.0V
J 0
(-1295 2682);
DISPLAY 0.340426 (-1295 2682);
PAINT SKYBLUE (-1295 2682);
DISPLAY INVISIBLE (-1295 2682);
FORCEPROP 1 LAST SIZE 1B
J 0
(-1175 2675);
DISPLAY 1.893617 (-1175 2675);
PAINT GREEN (-1175 2675);
DISPLAY INVISIBLE (-1175 2675);
FORCEPROP 2 LAST CDS_LIB mstr_symbols
J 0
(-1250 2725);
PAINT MONO (-1250 2725);
DISPLAY INVISIBLE (-1250 2725);
FORCEPROP 1 LAST PATH I118
J 0
(-1175 2725);
DISPLAY 0.872340 (-1175 2725);
PAINT AQUA (-1175 2725);
DISPLAY INVISIBLE (-1175 2725);
FORCEADD CAP_A..1
R 2
(-2250 1250);
FORCEPROP 1 LAST VOLTAGE 25V
J 2
(-2300 1250);
DISPLAY 0.617021 (-2300 1250);
PAINT SKYBLUE (-2300 1250);
FORCEPROP 1 LAST VALUE 0.01UF
J 2
(-2300 1300);
DISPLAY 0.617021 (-2300 1300);
PAINT SKYBLUE (-2300 1300);
FORCEPROP 1 LAST LOCATION C1M28
J 2
(-2300 1350);
DISPLAY 0.617021 (-2300 1350);
PAINT AQUA (-2300 1350);
FORCEPROP 0 LAST GROUP MCP
J 0
(-2475 1000);
DISPLAY 0.638298 (-2475 1000);
PAINT BROWN (-2475 1000);
DISPLAY BOTH (-2475 1000);
FORCEPROP 1 LAST PART_NUMBER A36096-045
J 2
(-2300 1100);
DISPLAY 0.617021 (-2300 1100);
PAINT BLUE (-2300 1100);
FORCEPROP 1 LAST MATERIAL X7R
J 2
(-2300 1150);
DISPLAY 0.617021 (-2300 1150);
PAINT SKYBLUE (-2300 1150);
FORCEPROP 1 LAST PACK_TYPE 0402V
J 2
(-2300 1050);
DISPLAY 0.617021 (-2300 1050);
PAINT SKYBLUE (-2300 1050);
FORCEPROP 1 LAST TOLERANCE 10%
J 2
(-2300 1200);
DISPLAY 0.617021 (-2300 1200);
PAINT SKYBLUE (-2300 1200);
FORCEPROP 1 LASTPIN (-2250 1150) $PN 2
J 2
(-2260 1130);
DISPLAY 0.617021 (-2260 1130);
PAINT ORANGE (-2260 1130);
FORCEPROP 1 LASTPIN (-2250 1350) $PN 1
J 2
(-2260 1330);
DISPLAY 0.617021 (-2260 1330);
PAINT ORANGE (-2260 1330);
FORCEPROP 2 LAST CDS_LIB dev_discrete
J 0
(-2250 1250);
PAINT ORANGE (-2250 1250);
DISPLAY INVISIBLE (-2250 1250);
FORCEPROP 2 LAST ROOM DEBUG
J 2
(-2300 1400);
DISPLAY 1.617021 (-2300 1400);
PAINT WHITE (-2300 1400);
DISPLAY INVISIBLE (-2300 1400);
FORCEPROP 1 LAST PATH I119
J 2
(-2300 1400);
DISPLAY 0.978723 (-2300 1400);
PAINT WHITE (-2300 1400);
DISPLAY INVISIBLE (-2300 1400);
FORCEPROP 2 LAST CDS_SEC 1
J 0
(-2300 1400);
PAINT ORANGE (-2300 1400);
DISPLAY INVISIBLE (-2300 1400);
FORCEPROP 2 LAST BOM_COST DEBUG
J 0
(-2300 1400);
DISPLAY 1.617021 (-2300 1400);
PAINT WHITE (-2300 1400);
DISPLAY INVISIBLE (-2300 1400);
FORCEPROP 2 LAST SEC 1
J 0
(-2300 1450);
DISPLAY 0.680851 (-2300 1450);
PAINT MONO (-2300 1450);
DISPLAY INVISIBLE (-2300 1450);
FORCEPROP 2 LAST SEC_TYPE 0402V
J 0
(-2300 1450);
DISPLAY 1.021277 (-2300 1450);
PAINT ORANGE (-2300 1450);
DISPLAY INVISIBLE (-2300 1450);
FORCEADD GND..1
(-2250 1050);
FORCEPROP 3 LASTPIN (-2250 1100) SIG_NAME GND\g
J 0
(-2240 1110);
DISPLAY 0.659574 (-2240 1110);
PAINT MONO (-2240 1110);
DISPLAY INVISIBLE (-2240 1110);
FORCEPROP 1 LAST HDL_POWER GND
J 0
(-2250 1200);
PAINT GREEN (-2250 1200);
DISPLAY INVISIBLE (-2250 1200);
FORCEPROP 1 LAST BODY_TYPE PLUMBING
J 0
(-2295 1007);
DISPLAY 0.340426 (-2295 1007);
PAINT GREEN (-2295 1007);
DISPLAY INVISIBLE (-2295 1007);
FORCEPROP 1 LAST VOLTAGE 0.0V
J 0
(-2295 1007);
DISPLAY 0.340426 (-2295 1007);
PAINT SKYBLUE (-2295 1007);
DISPLAY INVISIBLE (-2295 1007);
FORCEPROP 1 LAST SIZE 1B
J 0
(-2175 1000);
DISPLAY 1.893617 (-2175 1000);
PAINT GREEN (-2175 1000);
DISPLAY INVISIBLE (-2175 1000);
FORCEPROP 2 LAST ROOM DEBUG
J 0
(-2725 1125);
DISPLAY 1.617021 (-2725 1125);
PAINT WHITE (-2725 1125);
DISPLAY INVISIBLE (-2725 1125);
FORCEPROP 2 LAST BOM_COST DEBUG
J 0
(-2725 1175);
DISPLAY 1.617021 (-2725 1175);
PAINT WHITE (-2725 1175);
DISPLAY INVISIBLE (-2725 1175);
FORCEPROP 2 LAST CDS_LIB mstr_symbols
J 0
(-2250 1050);
PAINT MONO (-2250 1050);
DISPLAY INVISIBLE (-2250 1050);
FORCEPROP 1 LAST PATH I121
J 0
(-2175 1050);
DISPLAY 0.872340 (-2175 1050);
PAINT AQUA (-2175 1050);
DISPLAY INVISIBLE (-2175 1050);
FORCEADD OFFPAGE..5
(-3125 4625);
FORCEPROP 2 LAST $XR0 29 
J 0
(-3349 4625);
DISPLAY 0.638298 (-3349 4625);
PAINT MONO (-3349 4625);
FORCEPROP 2 LAST $XR2 113 
J 0
(-3559 4625);
DISPLAY 0.638298 (-3559 4625);
PAINT MONO (-3559 4625);
FORCEPROP 2 LAST $XR1 63 
J 0
(-3439 4625);
DISPLAY 0.638298 (-3439 4625);
PAINT MONO (-3439 4625);
FORCEPROP 1 LAST COMMENT_BODY TRUE
J 0
(-3025 4550);
DISPLAY 0.872340 (-3025 4550);
PAINT GREEN (-3025 4550);
DISPLAY INVISIBLE (-3025 4550);
FORCEPROP 1 LAST OFFPAGE TRUE
J 0
(-2800 4500);
DISPLAY 0.872340 (-2800 4500);
PAINT GREEN (-2800 4500);
DISPLAY INVISIBLE (-2800 4500);
FORCEPROP 2 LAST CDS_LIB mstr_standard
J 0
(-3125 4625);
PAINT MONO (-3125 4625);
DISPLAY INVISIBLE (-3125 4625);
FORCEPROP 2 LAST PATH I124
J 0
(-3075 4700);
DISPLAY 1.021277 (-3075 4700);
PAINT ORANGE (-3075 4700);
DISPLAY INVISIBLE (-3075 4700);
FORCEADD OFFPAGE..5
(-3125 4375);
FORCEPROP 2 LAST $XR1 29 
J 0
(-3470 4375);
DISPLAY 0.638298 (-3470 4375);
PAINT MONO (-3470 4375);
FORCEPROP 2 LAST $XR2 63 
J 0
(-3560 4375);
DISPLAY 0.638298 (-3560 4375);
PAINT MONO (-3560 4375);
FORCEPROP 2 LAST $XR0 113 
J 0
(-3380 4375);
DISPLAY 0.638298 (-3380 4375);
PAINT MONO (-3380 4375);
FORCEPROP 1 LAST COMMENT_BODY TRUE
J 0
(-3025 4300);
DISPLAY 0.872340 (-3025 4300);
PAINT GREEN (-3025 4300);
DISPLAY INVISIBLE (-3025 4300);
FORCEPROP 1 LAST OFFPAGE TRUE
J 0
(-2800 4250);
DISPLAY 0.872340 (-2800 4250);
PAINT GREEN (-2800 4250);
DISPLAY INVISIBLE (-2800 4250);
FORCEPROP 2 LAST CDS_LIB mstr_standard
J 0
(-3125 4375);
PAINT MONO (-3125 4375);
DISPLAY INVISIBLE (-3125 4375);
FORCEPROP 2 LAST PATH I126
J 0
(-3075 4450);
DISPLAY 1.021277 (-3075 4450);
PAINT ORANGE (-3075 4450);
DISPLAY INVISIBLE (-3075 4450);
FORCEADD 74CBTLV1G125..1
(-1500 850);
FORCEPROP 2 LASTPIN (-1250 850) $PN 4
J 0
(-1240 860);
DISPLAY 0.617021 (-1240 860);
PAINT ORANGE (-1240 860);
FORCEPROP 1 LAST POWER_GROUP VCC=P3V3_STBY;GND=GND;
J 0
(-1725 650);
DISPLAY 0.617021 (-1725 650);
PAINT ORANGE (-1725 650);
FORCEPROP 1 LAST LOCATION U1M6
J 0
(-1666 981);
DISPLAY 0.617021 (-1666 981);
PAINT AQUA (-1666 981);
FORCEPROP 0 LAST GROUP MCP
J 0
(-1725 600);
DISPLAY 0.638298 (-1725 600);
PAINT BROWN (-1725 600);
DISPLAY BOTH (-1725 600);
FORCEPROP 1 LAST PACK_TYPE SMLF
J 0
(-1675 1020);
DISPLAY 0.617021 (-1675 1020);
PAINT SKYBLUE (-1675 1020);
FORCEPROP 1 LAST PART_NUMBER C88177-001
J 0
(-1665 710);
DISPLAY 0.617021 (-1665 710);
PAINT BLUE (-1665 710);
FORCEPROP 2 LASTPIN (-1750 850) $PN 2
J 2
(-1760 860);
DISPLAY 0.617021 (-1760 860);
PAINT ORANGE (-1760 860);
FORCEPROP 2 LASTPIN (-1750 800) $PN 1
J 2
(-1760 810);
DISPLAY 0.617021 (-1760 810);
PAINT ORANGE (-1760 810);
FORCEPROP 1 LAST MATERIAL IC
J 0
(-1675 1070);
DISPLAY 0.617021 (-1675 1070);
PAINT SKYBLUE (-1675 1070);
FORCEPROP 1 LAST PATH I127
J 0
(-1400 970);
DISPLAY 0.872340 (-1400 970);
PAINT PINK (-1400 970);
DISPLAY INVISIBLE (-1400 970);
FORCEPROP 2 LAST CDS_LIB mstr_ttl
J 0
(-1500 850);
PAINT MONO (-1500 850);
DISPLAY INVISIBLE (-1500 850);
FORCEPROP 2 LAST ROOM DEBUG
J 0
(-1675 1175);
DISPLAY 1.021277 (-1675 1175);
PAINT ORANGE (-1675 1175);
DISPLAY INVISIBLE (-1675 1175);
FORCEPROP 2 LAST SEC 1
J 0
(-1675 1100);
DISPLAY 0.680851 (-1675 1100);
PAINT MONO (-1675 1100);
DISPLAY INVISIBLE (-1675 1100);
FORCEPROP 2 LAST SEC_TYPE SMLF
J 0
(-1675 1100);
DISPLAY 1.021277 (-1675 1100);
PAINT ORANGE (-1675 1100);
DISPLAY INVISIBLE (-1675 1100);
FORCEPROP 2 LAST BOM_COST DEBUG
J 0
(-1675 1175);
DISPLAY 1.021277 (-1675 1175);
PAINT ORANGE (-1675 1175);
DISPLAY INVISIBLE (-1675 1175);
FORCEADD OFFPAGE..1
(-2475 850);
FORCEPROP 2 LAST $XR0 29 
J 0
(-2726 850);
DISPLAY 0.638298 (-2726 850);
PAINT MONO (-2726 850);
FORCEPROP 2 LAST $XR1 113 
J 0
(-2846 850);
DISPLAY 0.638298 (-2846 850);
PAINT MONO (-2846 850);
FORCEPROP 1 LAST COMMENT_BODY TRUE
J 0
(-2350 750);
DISPLAY 0.872340 (-2350 750);
PAINT GREEN (-2350 750);
DISPLAY INVISIBLE (-2350 750);
FORCEPROP 1 LAST OFFPAGE TRUE
J 0
(-2150 725);
DISPLAY 0.872340 (-2150 725);
PAINT GREEN (-2150 725);
DISPLAY INVISIBLE (-2150 725);
FORCEPROP 2 LAST CDS_LIB mstr_standard
J 0
(-2475 850);
PAINT MONO (-2475 850);
DISPLAY INVISIBLE (-2475 850);
FORCEPROP 2 LAST PATH I128
J 0
(-2425 925);
DISPLAY 1.021277 (-2425 925);
PAINT ORANGE (-2425 925);
DISPLAY INVISIBLE (-2425 925);
FORCEADD OFFPAGE..1
(2200 4400);
FORCEPROP 2 LAST $XR0 113 
J 0
(1948 4400);
DISPLAY 0.638298 (1948 4400);
PAINT MONO (1948 4400);
FORCEPROP 2 LAST $XR1 29 
J 0
(1858 4400);
DISPLAY 0.638298 (1858 4400);
PAINT MONO (1858 4400);
FORCEPROP 2 LAST $XR2 63 
J 0
(1768 4400);
DISPLAY 0.638298 (1768 4400);
PAINT MONO (1768 4400);
FORCEPROP 1 LAST COMMENT_BODY TRUE
J 0
(2325 4300);
DISPLAY 1.404255 (2325 4300);
PAINT PEACH (2325 4300);
DISPLAY INVISIBLE (2325 4300);
FORCEPROP 1 LAST OFFPAGE TRUE
J 0
(2525 4275);
DISPLAY 1.404255 (2525 4275);
PAINT GREEN (2525 4275);
DISPLAY INVISIBLE (2525 4275);
FORCEPROP 2 LAST PATH I143
J 0
(2250 4475);
DISPLAY 1.021277 (2250 4475);
PAINT ORANGE (2250 4475);
DISPLAY INVISIBLE (2250 4475);
FORCEPROP 2 LAST CDS_LIB mstr_standard
J 0
(2200 4400);
PAINT MONO (2200 4400);
DISPLAY INVISIBLE (2200 4400);
FORCEADD GND..1
(-975 4450);
FORCEPROP 3 LASTPIN (-975 4500) SIG_NAME GND\g
J 0
(-965 4510);
DISPLAY 0.659574 (-965 4510);
PAINT MONO (-965 4510);
DISPLAY INVISIBLE (-965 4510);
FORCEPROP 1 LAST HDL_POWER GND
J 0
(-975 4600);
PAINT GREEN (-975 4600);
DISPLAY INVISIBLE (-975 4600);
FORCEPROP 1 LAST BODY_TYPE PLUMBING
J 0
(-1020 4407);
DISPLAY 0.340426 (-1020 4407);
PAINT GREEN (-1020 4407);
DISPLAY INVISIBLE (-1020 4407);
FORCEPROP 2 LAST ROOM DEBUG
J 0
(-1450 4525);
DISPLAY 1.617021 (-1450 4525);
PAINT WHITE (-1450 4525);
DISPLAY INVISIBLE (-1450 4525);
FORCEPROP 2 LAST BOM_COST DEBUG
J 0
(-1450 4575);
DISPLAY 1.617021 (-1450 4575);
PAINT WHITE (-1450 4575);
DISPLAY INVISIBLE (-1450 4575);
FORCEPROP 1 LAST VOLTAGE 0.0V
J 0
(-1020 4407);
DISPLAY 0.340426 (-1020 4407);
PAINT SKYBLUE (-1020 4407);
DISPLAY INVISIBLE (-1020 4407);
FORCEPROP 1 LAST SIZE 1B
J 0
(-900 4400);
DISPLAY 1.893617 (-900 4400);
PAINT GREEN (-900 4400);
DISPLAY INVISIBLE (-900 4400);
FORCEPROP 2 LAST CDS_LIB mstr_symbols
J 0
(-975 4450);
PAINT MONO (-975 4450);
DISPLAY INVISIBLE (-975 4450);
FORCEPROP 1 LAST PATH I146
J 0
(-900 4450);
DISPLAY 0.872340 (-900 4450);
PAINT AQUA (-900 4450);
DISPLAY INVISIBLE (-900 4450);
FORCEADD CAP_A..1
(-975 4650);
FORCEPROP 1 LAST PART_NUMBER A36096-030
J 0
(-925 4500);
DISPLAY 0.617021 (-925 4500);
PAINT BLUE (-925 4500);
FORCEPROP 1 LAST PACK_TYPE 0402V
J 0
(-925 4450);
DISPLAY 0.617021 (-925 4450);
PAINT SKYBLUE (-925 4450);
FORCEPROP 1 LASTPIN (-975 4550) $PN 2
J 0
(-965 4530);
DISPLAY 0.617021 (-965 4530);
PAINT ORANGE (-965 4530);
FORCEPROP 1 LAST MATERIAL X7R
J 0
(-925 4550);
DISPLAY 0.617021 (-925 4550);
PAINT SKYBLUE (-925 4550);
FORCEPROP 1 LASTPIN (-975 4750) $PN 1
J 0
(-965 4730);
DISPLAY 0.617021 (-965 4730);
PAINT ORANGE (-965 4730);
FORCEPROP 1 LAST TOLERANCE 10%
J 0
(-925 4600);
DISPLAY 0.617021 (-925 4600);
PAINT SKYBLUE (-925 4600);
FORCEPROP 1 LAST VOLTAGE 16V
J 0
(-925 4650);
DISPLAY 0.617021 (-925 4650);
PAINT SKYBLUE (-925 4650);
FORCEPROP 1 LAST VALUE 0.1UF
J 0
(-925 4700);
DISPLAY 0.617021 (-925 4700);
PAINT SKYBLUE (-925 4700);
FORCEPROP 1 LAST LOCATION C1M29
J 0
(-925 4750);
DISPLAY 0.617021 (-925 4750);
PAINT AQUA (-925 4750);
FORCEPROP 0 LAST GROUP MCP
J 0
(-750 4750);
DISPLAY 0.638298 (-750 4750);
PAINT BROWN (-750 4750);
DISPLAY BOTH (-750 4750);
FORCEPROP 2 LAST CDS_LIB dev_discrete
J 0
(-975 4650);
PAINT ORANGE (-975 4650);
DISPLAY INVISIBLE (-975 4650);
FORCEPROP 1 LAST PATH I147
J 0
(-925 4800);
DISPLAY 0.978723 (-925 4800);
PAINT WHITE (-925 4800);
DISPLAY INVISIBLE (-925 4800);
FORCEPROP 2 LAST $SEC 1
J 0
(-925 4850);
PAINT MONO (-925 4850);
DISPLAY INVISIBLE (-925 4850);
FORCEPROP 2 LAST CDS_SEC 1
J 0
(-925 4850);
PAINT MONO (-925 4850);
DISPLAY INVISIBLE (-925 4850);
FORCEPROP 2 LAST ROOM DEBUG
J 0
(-925 4850);
DISPLAY 1.021277 (-925 4850);
PAINT ORANGE (-925 4850);
DISPLAY INVISIBLE (-925 4850);
FORCEADD OFFPAGE..5
(-3000 3525);
FORCEPROP 2 LAST $XR0 113 
J 0
(-3285 3525);
DISPLAY 0.638298 (-3285 3525);
PAINT MONO (-3285 3525);
FORCEPROP 1 LAST COMMENT_BODY TRUE
J 0
(-2900 3450);
DISPLAY 0.872340 (-2900 3450);
PAINT GREEN (-2900 3450);
DISPLAY INVISIBLE (-2900 3450);
FORCEPROP 1 LAST OFFPAGE TRUE
J 0
(-2675 3400);
DISPLAY 0.872340 (-2675 3400);
PAINT GREEN (-2675 3400);
DISPLAY INVISIBLE (-2675 3400);
FORCEPROP 2 LAST CDS_LIB mstr_standard
J 0
(-3000 3525);
PAINT MONO (-3000 3525);
DISPLAY INVISIBLE (-3000 3525);
FORCEPROP 2 LAST PATH I153
J 0
(-2950 3600);
DISPLAY 1.021277 (-2950 3600);
PAINT ORANGE (-2950 3600);
DISPLAY INVISIBLE (-2950 3600);
FORCEADD OFFPAGE..4
(-1050 3575);
FORCEPROP 2 LAST $XR0 63 
J 0
(-864 3575);
DISPLAY 0.638298 (-864 3575);
PAINT MONO (-864 3575);
FORCEPROP 1 LAST COMMENT_BODY TRUE
J 0
(-1075 3475);
DISPLAY 0.872340 (-1075 3475);
PAINT GREEN (-1075 3475);
DISPLAY INVISIBLE (-1075 3475);
FORCEPROP 1 LAST OFFPAGE TRUE
J 0
(-725 3450);
DISPLAY 0.872340 (-725 3450);
PAINT GREEN (-725 3450);
DISPLAY INVISIBLE (-725 3450);
FORCEPROP 2 LAST CDS_LIB mstr_standard
J 0
(-1050 3575);
PAINT MONO (-1050 3575);
DISPLAY INVISIBLE (-1050 3575);
FORCEPROP 2 LAST PATH I154
J 0
(-875 3650);
DISPLAY 1.021277 (-875 3650);
PAINT ORANGE (-875 3650);
DISPLAY INVISIBLE (-875 3650);
FORCEADD OFFPAGE..4
(-1050 3475);
FORCEPROP 2 LAST $XR0 29 
J 0
(-864 3475);
DISPLAY 0.638298 (-864 3475);
PAINT MONO (-864 3475);
FORCEPROP 2 LAST $XR1 113 
J 0
(-774 3475);
DISPLAY 0.638298 (-774 3475);
PAINT MONO (-774 3475);
FORCEPROP 1 LAST COMMENT_BODY TRUE
J 0
(-1075 3375);
DISPLAY 0.872340 (-1075 3375);
PAINT GREEN (-1075 3375);
DISPLAY INVISIBLE (-1075 3375);
FORCEPROP 1 LAST OFFPAGE TRUE
J 0
(-725 3350);
DISPLAY 0.872340 (-725 3350);
PAINT GREEN (-725 3350);
DISPLAY INVISIBLE (-725 3350);
FORCEPROP 2 LAST CDS_LIB mstr_standard
J 0
(-1050 3475);
PAINT MONO (-1050 3475);
DISPLAY INVISIBLE (-1050 3475);
FORCEPROP 2 LAST PATH I155
J 0
(-875 3550);
DISPLAY 1.021277 (-875 3550);
PAINT ORANGE (-875 3550);
DISPLAY INVISIBLE (-875 3550);
FORCEADD P3V3_STBY..1
(-1250 3300);
FORCEPROP 3 LASTPIN (-1250 3250) SIG_NAME P3V3_STBY\g
J 0
(-1240 3260);
DISPLAY 0.659574 (-1240 3260);
PAINT MONO (-1240 3260);
DISPLAY INVISIBLE (-1240 3260);
FORCEPROP 1 LAST HDL_POWER P3V3_STBY
J 0
(-1550 3175);
DISPLAY 0.872340 (-1550 3175);
PAINT ORANGE (-1550 3175);
DISPLAY INVISIBLE (-1550 3175);
FORCEPROP 1 LAST BODY_TYPE PLUMBING
J 0
(-1295 3257);
DISPLAY 0.340426 (-1295 3257);
PAINT GREEN (-1295 3257);
DISPLAY INVISIBLE (-1295 3257);
FORCEPROP 1 LAST VOLTAGE 3.3V
J 0
(-1295 3257);
DISPLAY 0.340426 (-1295 3257);
PAINT SKYBLUE (-1295 3257);
DISPLAY INVISIBLE (-1295 3257);
FORCEPROP 1 LAST PATH I160
J 0
(-1205 3302);
DISPLAY 0.340426 (-1205 3302);
PAINT GREEN (-1205 3302);
DISPLAY INVISIBLE (-1205 3302);
FORCEPROP 1 LAST SIZE 1B
J 0
(-1205 3322);
DISPLAY 0.340426 (-1205 3322);
PAINT GREEN (-1205 3322);
DISPLAY INVISIBLE (-1205 3322);
FORCEPROP 2 LAST CDS_LIB mstr_symbols
J 0
(-1250 3300);
PAINT ORANGE (-1250 3300);
DISPLAY INVISIBLE (-1250 3300);
FORCEADD P3V3_STBY..1
(-2250 1450);
FORCEPROP 3 LASTPIN (-2250 1400) SIG_NAME P3V3_STBY\g
J 0
(-2240 1410);
DISPLAY 0.659574 (-2240 1410);
PAINT MONO (-2240 1410);
DISPLAY INVISIBLE (-2240 1410);
FORCEPROP 1 LAST HDL_POWER P3V3_STBY
J 0
(-2550 1325);
DISPLAY 0.872340 (-2550 1325);
PAINT ORANGE (-2550 1325);
DISPLAY INVISIBLE (-2550 1325);
FORCEPROP 1 LAST BODY_TYPE PLUMBING
J 0
(-2295 1407);
DISPLAY 0.340426 (-2295 1407);
PAINT GREEN (-2295 1407);
DISPLAY INVISIBLE (-2295 1407);
FORCEPROP 1 LAST VOLTAGE 3.3V
J 0
(-2295 1407);
DISPLAY 0.340426 (-2295 1407);
PAINT SKYBLUE (-2295 1407);
DISPLAY INVISIBLE (-2295 1407);
FORCEPROP 1 LAST PATH I161
J 0
(-2205 1452);
DISPLAY 0.340426 (-2205 1452);
PAINT GREEN (-2205 1452);
DISPLAY INVISIBLE (-2205 1452);
FORCEPROP 2 LAST CDS_LIB mstr_symbols
J 0
(-2250 1450);
PAINT ORANGE (-2250 1450);
DISPLAY INVISIBLE (-2250 1450);
FORCEPROP 1 LAST SIZE 1B
J 0
(-2205 1472);
DISPLAY 0.340426 (-2205 1472);
PAINT GREEN (-2205 1472);
DISPLAY INVISIBLE (-2205 1472);
FORCEADD OFFPAGE..1
(-3125 4425);
FORCEPROP 2 LAST $XR0 113 
J 0
(-3377 4425);
DISPLAY 0.638298 (-3377 4425);
PAINT MONO (-3377 4425);
FORCEPROP 1 LAST COMMENT_BODY TRUE
J 0
(-3000 4325);
DISPLAY 0.872340 (-3000 4325);
PAINT GREEN (-3000 4325);
DISPLAY INVISIBLE (-3000 4325);
FORCEPROP 1 LAST OFFPAGE TRUE
J 0
(-2800 4300);
DISPLAY 0.872340 (-2800 4300);
PAINT GREEN (-2800 4300);
DISPLAY INVISIBLE (-2800 4300);
FORCEPROP 2 LAST PATH I162
J 0
(-3375 4475);
DISPLAY 1.021277 (-3375 4475);
PAINT ORANGE (-3375 4475);
DISPLAY INVISIBLE (-3375 4475);
FORCEPROP 2 LAST CDS_LIB mstr_standard
J 0
(-3125 4425);
PAINT MONO (-3125 4425);
DISPLAY INVISIBLE (-3125 4425);
FORCEADD OFFPAGE..5
(-3125 3975);
FORCEPROP 2 LAST $XR0 113 
J 0
(-3380 3975);
DISPLAY 0.638298 (-3380 3975);
PAINT MONO (-3380 3975);
FORCEPROP 1 LAST COMMENT_BODY TRUE
J 0
(-3025 3900);
DISPLAY 0.872340 (-3025 3900);
PAINT GREEN (-3025 3900);
DISPLAY INVISIBLE (-3025 3900);
FORCEPROP 1 LAST OFFPAGE TRUE
J 0
(-2800 3850);
DISPLAY 0.872340 (-2800 3850);
PAINT GREEN (-2800 3850);
DISPLAY INVISIBLE (-2800 3850);
FORCEPROP 2 LAST PATH I163
J 0
(-3375 4025);
DISPLAY 1.021277 (-3375 4025);
PAINT ORANGE (-3375 4025);
DISPLAY INVISIBLE (-3375 4025);
FORCEPROP 2 LAST CDS_LIB mstr_standard
J 0
(-3125 3975);
PAINT MONO (-3125 3975);
DISPLAY INVISIBLE (-3125 3975);
FORCEADD RES..1
(-2600 4150);
FORCEPROP 1 LAST VALUE 1.00K
J 2
(-2725 4100);
DISPLAY 0.617021 (-2725 4100);
PAINT SKYBLUE (-2725 4100);
FORCEPROP 1 LAST TOLERANCE 1%
J 0
(-2700 4100);
DISPLAY 0.617021 (-2700 4100);
PAINT SKYBLUE (-2700 4100);
FORCEPROP 1 LAST MATERIAL CHIP
J 0
(-2475 4100);
DISPLAY 0.617021 (-2475 4100);
PAINT SKYBLUE (-2475 4100);
FORCEPROP 1 LASTPIN (-2500 4150) $PN 2
J 0
(-2538 4162);
DISPLAY 0.617021 (-2538 4162);
PAINT ORANGE (-2538 4162);
FORCEPROP 1 LAST LOCATION R9B14
J 0
(-2650 4200);
DISPLAY 0.617021 (-2650 4200);
PAINT AQUA (-2650 4200);
FORCEPROP 1 LASTPIN (-2700 4150) $PN 1
J 0
(-2688 4162);
DISPLAY 0.617021 (-2688 4162);
PAINT ORANGE (-2688 4162);
FORCEPROP 1 LAST WATTAGE 1/16W
J 2
(-2500 4100);
DISPLAY 0.617021 (-2500 4100);
PAINT SKYBLUE (-2500 4100);
FORCEPROP 1 LAST PART_NUMBER G21796-026
J 0
(-2625 4050);
DISPLAY 0.617021 (-2625 4050);
PAINT BLUE (-2625 4050);
FORCEPROP 1 LAST PACK_TYPE 0402
J 0
(-2725 4050);
DISPLAY 0.617021 (-2725 4050);
PAINT SKYBLUE (-2725 4050);
FORCEPROP 0 LAST GROUP MCP
J 0
(-2400 4050);
DISPLAY 0.638298 (-2400 4050);
PAINT BROWN (-2400 4050);
DISPLAY BOTH (-2400 4050);
FORCEPROP 2 LAST CDS_LIB mstr_discrete
J 0
(-2600 4150);
PAINT ORANGE (-2600 4150);
DISPLAY INVISIBLE (-2600 4150);
FORCEPROP 1 LAST PATH I168
J 0
(-2650 4300);
DISPLAY 0.978723 (-2650 4300);
PAINT WHITE (-2650 4300);
DISPLAY INVISIBLE (-2650 4300);
FORCEPROP 2 LAST SEC 1
J 0
(-2650 4350);
DISPLAY 0.680851 (-2650 4350);
PAINT MONO (-2650 4350);
DISPLAY INVISIBLE (-2650 4350);
FORCEPROP 2 LAST SEC_TYPE 0402
J 0
(-2650 4350);
DISPLAY 1.021277 (-2650 4350);
PAINT ORANGE (-2650 4350);
DISPLAY INVISIBLE (-2650 4350);
FORCEPROP 2 LAST ROOM DEBUG
J 0
(-2555 4315);
DISPLAY 1.276596 (-2555 4315);
PAINT WHITE (-2555 4315);
DISPLAY INVISIBLE (-2555 4315);
FORCEADD OFFPAGE..1
(-3125 4150);
FORCEPROP 2 LAST $XR0 96 
J 0
(-3346 4150);
DISPLAY 0.638298 (-3346 4150);
PAINT MONO (-3346 4150);
FORCEPROP 2 LAST $XR1 21 
J 0
(-3436 4150);
DISPLAY 0.638298 (-3436 4150);
PAINT MONO (-3436 4150);
FORCEPROP 1 LAST COMMENT_BODY TRUE
J 0
(-3000 4050);
DISPLAY 0.872340 (-3000 4050);
PAINT GREEN (-3000 4050);
DISPLAY INVISIBLE (-3000 4050);
FORCEPROP 1 LAST OFFPAGE TRUE
J 0
(-2800 4025);
DISPLAY 0.872340 (-2800 4025);
PAINT GREEN (-2800 4025);
DISPLAY INVISIBLE (-2800 4025);
FORCEPROP 2 LAST PATH I169
J 0
(-3075 4225);
DISPLAY 1.021277 (-3075 4225);
PAINT ORANGE (-3075 4225);
DISPLAY INVISIBLE (-3075 4225);
FORCEPROP 2 LAST CDS_LIB mstr_standard
J 0
(-3125 4150);
PAINT ORANGE (-3125 4150);
DISPLAY INVISIBLE (-3125 4150);
FORCEADD VCC_CORE..1
(-1100 4900);
FORCEPROP 3 LASTPIN (-1100 4850) SIG_NAME P1V8_MCP_CPU0\g
J 0
(-1090 4860);
DISPLAY 0.659574 (-1090 4860);
PAINT MONO (-1090 4860);
DISPLAY INVISIBLE (-1090 4860);
FORCEPROP 1 LAST HDL_POWER P1V8_MCP_CPU0
J 1
(-1100 4950);
DISPLAY 0.617021 (-1100 4950);
PAINT GREEN (-1100 4950);
FORCEPROP 1 LAST PATH I171
J 0
(-1050 4925);
DISPLAY 0.872340 (-1050 4925);
PAINT AQUA (-1050 4925);
DISPLAY INVISIBLE (-1050 4925);
FORCEPROP 2 LAST CDS_LIB mstr_symbols
J 0
(-1100 4900);
PAINT ORANGE (-1100 4900);
DISPLAY INVISIBLE (-1100 4900);
FORCEADD OFFPAGE..1
(950 4400);
FORCEPROP 2 LAST $XR0 113 
J 0
(668 4400);
DISPLAY 0.638298 (668 4400);
PAINT MONO (668 4400);
FORCEPROP 2 LAST $XR1 29 
J 0
(578 4400);
DISPLAY 0.638298 (578 4400);
PAINT MONO (578 4400);
FORCEPROP 2 LAST $XR2 63 
J 0
(488 4400);
DISPLAY 0.638298 (488 4400);
PAINT MONO (488 4400);
FORCEPROP 1 LAST COMMENT_BODY TRUE
J 0
(1075 4300);
DISPLAY 1.404255 (1075 4300);
PAINT PEACH (1075 4300);
DISPLAY INVISIBLE (1075 4300);
FORCEPROP 1 LAST OFFPAGE TRUE
J 0
(1275 4275);
DISPLAY 1.404255 (1275 4275);
PAINT GREEN (1275 4275);
DISPLAY INVISIBLE (1275 4275);
FORCEPROP 2 LAST PATH I172
J 0
(700 4450);
DISPLAY 1.021277 (700 4450);
PAINT ORANGE (700 4450);
DISPLAY INVISIBLE (700 4450);
FORCEPROP 2 LAST CDS_LIB mstr_standard
J 0
(950 4400);
PAINT MONO (950 4400);
DISPLAY INVISIBLE (950 4400);
FORCEADD SCONN10_C12536004..1
(-1375 4375);
FORCEPROP 1 LAST PART_NUMBER C12536-004
J 0
(-1525 4175);
DISPLAY 0.617021 (-1525 4175);
PAINT BLUE (-1525 4175);
FORCEPROP 2 LASTPIN (-1225 4325) $PN 8
J 0
(-1215 4335);
DISPLAY 0.617021 (-1215 4335);
PAINT ORANGE (-1215 4335);
FORCEPROP 2 LASTPIN (-1225 4375) $PN 6
J 0
(-1215 4385);
DISPLAY 0.617021 (-1215 4385);
PAINT ORANGE (-1215 4385);
FORCEPROP 1 LAST MATERIAL CONN
J 0
(-1475 4600);
DISPLAY 0.617021 (-1475 4600);
PAINT SKYBLUE (-1475 4600);
FORCEPROP 2 LASTPIN (-1225 4275) $PN 10
J 0
(-1215 4285);
DISPLAY 0.617021 (-1215 4285);
PAINT ORANGE (-1215 4285);
FORCEPROP 2 LASTPIN (-1525 4325) $PN 7
J 2
(-1535 4335);
DISPLAY 0.617021 (-1535 4335);
PAINT ORANGE (-1535 4335);
FORCEPROP 2 LASTPIN (-1525 4475) $PN 1
J 2
(-1535 4485);
DISPLAY 0.617021 (-1535 4485);
PAINT ORANGE (-1535 4485);
FORCEPROP 2 LASTPIN (-1525 4425) $PN 3
J 2
(-1535 4435);
DISPLAY 0.617021 (-1535 4435);
PAINT ORANGE (-1535 4435);
FORCEPROP 2 LASTPIN (-1525 4375) $PN 5
J 2
(-1535 4385);
DISPLAY 0.617021 (-1535 4385);
PAINT ORANGE (-1535 4385);
FORCEPROP 2 LASTPIN (-1525 4275) $PN 9
J 2
(-1535 4285);
DISPLAY 0.617021 (-1535 4285);
PAINT ORANGE (-1535 4285);
FORCEPROP 2 LASTPIN (-1225 4425) $PN 4
J 0
(-1215 4435);
DISPLAY 0.617021 (-1215 4435);
PAINT ORANGE (-1215 4435);
FORCEPROP 2 LASTPIN (-1225 4475) $PN 2
J 0
(-1215 4485);
DISPLAY 0.617021 (-1215 4485);
PAINT ORANGE (-1215 4485);
FORCEPROP 0 LAST GROUP MCP
J 0
(-1525 4125);
DISPLAY 0.638298 (-1525 4125);
PAINT BROWN (-1525 4125);
DISPLAY BOTH (-1525 4125);
FORCEPROP 1 LAST LOCATION J9B4
J 0
(-1475 4650);
DISPLAY 0.617021 (-1475 4650);
PAINT AQUA (-1475 4650);
FORCEPROP 2 LAST ROOM DEBUG
J 0
(-1625 4800);
DISPLAY 1.021277 (-1625 4800);
PAINT ORANGE (-1625 4800);
DISPLAY INVISIBLE (-1625 4800);
FORCEPROP 2 LAST SEC 1
J 0
(-1625 4750);
DISPLAY 0.680851 (-1625 4750);
PAINT MONO (-1625 4750);
DISPLAY INVISIBLE (-1625 4750);
FORCEPROP 2 LAST SEC_TYPE SMLF
J 0
(-1625 4750);
DISPLAY 1.021277 (-1625 4750);
PAINT ORANGE (-1625 4750);
DISPLAY INVISIBLE (-1625 4750);
FORCEPROP 1 LAST PACK_TYPE SMLF
J 0
(-1475 4100);
DISPLAY 0.978723 (-1475 4100);
PAINT SKYBLUE (-1475 4100);
DISPLAY INVISIBLE (-1475 4100);
FORCEPROP 2 LAST CDS_LIB mstr_sconn
J 0
(-1375 4375);
PAINT ORANGE (-1375 4375);
DISPLAY INVISIBLE (-1375 4375);
FORCEPROP 1 LAST PATH I175
J 0
(-1025 4600);
DISPLAY 0.936170 (-1025 4600);
PAINT GREEN (-1025 4600);
DISPLAY INVISIBLE (-1025 4600);
FORCEADD OFFPAGE..2
(-550 4375);
FORCEPROP 2 LAST $XR0 29 
J 0
(-361 4375);
DISPLAY 0.638298 (-361 4375);
PAINT MONO (-361 4375);
FORCEPROP 2 LAST $XR2 113 
J 0
(-181 4375);
DISPLAY 0.638298 (-181 4375);
PAINT MONO (-181 4375);
FORCEPROP 2 LAST $XR1 63 
J 0
(-271 4375);
DISPLAY 0.638298 (-271 4375);
PAINT MONO (-271 4375);
FORCEPROP 1 LAST COMMENT_BODY TRUE
J 0
(-595 4280);
DISPLAY 0.872340 (-595 4280);
PAINT GREEN (-595 4280);
DISPLAY INVISIBLE (-595 4280);
FORCEPROP 1 LAST OFFPAGE TRUE
J 0
(-225 4250);
DISPLAY 0.872340 (-225 4250);
PAINT GREEN (-225 4250);
DISPLAY INVISIBLE (-225 4250);
FORCEPROP 2 LAST CDS_LIB mstr_standard
J 0
(-550 4375);
PAINT MONO (-550 4375);
DISPLAY INVISIBLE (-550 4375);
FORCEPROP 2 LAST PATH I176
J 0
(-175 4425);
DISPLAY 1.021277 (-175 4425);
PAINT ORANGE (-175 4425);
DISPLAY INVISIBLE (-175 4425);
FORCEADD RES..2
R 2
(2600 4150);
FORCEPROP 1 LAST TOLERANCE 1%
J 2
(2555 4175);
DISPLAY 0.617021 (2555 4175);
PAINT SKYBLUE (2555 4175);
FORCEPROP 0 LAST GROUP MCP
J 0
(2300 3925);
DISPLAY 0.638298 (2300 3925);
PAINT BROWN (2300 3925);
DISPLAY BOTH (2300 3925);
FORCEPROP 1 LAST PACK_TYPE 0402
J 2
(2560 3975);
DISPLAY 0.617021 (2560 3975);
PAINT SKYBLUE (2560 3975);
FORCEPROP 1 LAST PART_NUMBER G21796-026
J 2
(2560 4025);
DISPLAY 0.617021 (2560 4025);
PAINT BLUE (2560 4025);
FORCEPROP 1 LAST LOCATION R9B9
J 2
(2555 4275);
DISPLAY 0.617021 (2555 4275);
PAINT AQUA (2555 4275);
FORCEPROP 1 LAST VALUE 1.00K
J 2
(2555 4225);
DISPLAY 0.617021 (2555 4225);
PAINT SKYBLUE (2555 4225);
FORCEPROP 1 LAST MATERIAL CHIP
J 2
(2560 4075);
DISPLAY 0.617021 (2560 4075);
PAINT SKYBLUE (2560 4075);
FORCEPROP 1 LASTPIN (2600 4050) $PN 2
J 2
(2595 4060);
DISPLAY 0.617021 (2595 4060);
PAINT ORANGE (2595 4060);
FORCEPROP 1 LASTPIN (2600 4250) $PN 1
J 2
(2595 4212);
DISPLAY 0.617021 (2595 4212);
PAINT ORANGE (2595 4212);
FORCEPROP 1 LAST WATTAGE 1/16W
J 2
(2560 4125);
DISPLAY 0.617021 (2560 4125);
PAINT SKYBLUE (2560 4125);
FORCEPROP 1 LAST PATH I179
J 2
(2550 4325);
DISPLAY 0.978723 (2550 4325);
PAINT WHITE (2550 4325);
DISPLAY INVISIBLE (2550 4325);
FORCEPROP 2 LAST SEC 1
J 2
(2550 4375);
DISPLAY 0.680851 (2550 4375);
PAINT MONO (2550 4375);
DISPLAY INVISIBLE (2550 4375);
FORCEPROP 2 LAST SEC_TYPE 0402
J 2
(2550 4375);
DISPLAY 1.021277 (2550 4375);
PAINT ORANGE (2550 4375);
DISPLAY INVISIBLE (2550 4375);
FORCEPROP 2 LAST CDS_LIB mstr_discrete
J 2
(2600 4150);
PAINT ORANGE (2600 4150);
DISPLAY INVISIBLE (2600 4150);
FORCEADD RES..1
(2800 4400);
FORCEPROP 0 LAST POP NOPOP
J 0
(2725 4200);
DISPLAY 0.638298 (2725 4200);
PAINT RED (2725 4200);
FORCEPROP 1 LAST PART_NUMBER G21796-047
J 0
(2750 4500);
DISPLAY 0.617021 (2750 4500);
PAINT BLUE (2750 4500);
FORCEPROP 1 LAST LOCATION R9B10
J 0
(2750 4450);
DISPLAY 0.617021 (2750 4450);
PAINT AQUA (2750 4450);
FORCEPROP 1 LAST PACK_TYPE 0402
J 0
(2875 4300);
DISPLAY 0.617021 (2875 4300);
PAINT SKYBLUE (2875 4300);
FORCEPROP 1 LAST MATERIAL CHIP
J 0
(2800 4250);
DISPLAY 0.617021 (2800 4250);
PAINT SKYBLUE (2800 4250);
FORCEPROP 1 LASTPIN (2700 4400) $PN 1
J 0
(2712 4412);
DISPLAY 0.617021 (2712 4412);
PAINT ORANGE (2712 4412);
FORCEPROP 1 LASTPIN (2900 4400) $PN 2
J 0
(2862 4412);
DISPLAY 0.617021 (2862 4412);
PAINT ORANGE (2862 4412);
FORCEPROP 1 LAST WATTAGE 1/16W
J 2
(2775 4250);
DISPLAY 0.617021 (2775 4250);
PAINT SKYBLUE (2775 4250);
FORCEPROP 1 LAST VALUE 49.9
J 2
(2775 4300);
DISPLAY 0.617021 (2775 4300);
PAINT SKYBLUE (2775 4300);
FORCEPROP 1 LAST TOLERANCE 1%
J 0
(2800 4300);
DISPLAY 0.617021 (2800 4300);
PAINT SKYBLUE (2800 4300);
FORCEPROP 2 LAST CDS_LIB mstr_discrete
J 0
(2800 4400);
PAINT ORANGE (2800 4400);
DISPLAY INVISIBLE (2800 4400);
FORCEPROP 1 LAST PATH I180
J 0
(2750 4550);
DISPLAY 0.978723 (2750 4550);
PAINT WHITE (2750 4550);
DISPLAY INVISIBLE (2750 4550);
FORCEPROP 2 LAST ROOM DEBUG
J 0
(2850 4575);
DISPLAY 1.617021 (2850 4575);
PAINT WHITE (2850 4575);
DISPLAY INVISIBLE (2850 4575);
FORCEPROP 2 LAST SEC 1
J 0
(2750 4600);
DISPLAY 0.680851 (2750 4600);
PAINT MONO (2750 4600);
DISPLAY INVISIBLE (2750 4600);
FORCEPROP 2 LAST SEC_TYPE 0402
J 0
(2750 4600);
DISPLAY 1.021277 (2750 4600);
PAINT ORANGE (2750 4600);
DISPLAY INVISIBLE (2750 4600);
FORCEPROP 2 LAST BOM_COST DEBUG
J 0
(2850 4575);
DISPLAY 1.617021 (2850 4575);
PAINT WHITE (2850 4575);
DISPLAY INVISIBLE (2850 4575);
FORCEADD GND..1
(2600 3950);
FORCEPROP 3 LASTPIN (2600 4000) SIG_NAME GND\g
J 0
(2610 4010);
DISPLAY 0.659574 (2610 4010);
PAINT MONO (2610 4010);
DISPLAY INVISIBLE (2610 4010);
FORCEPROP 1 LAST HDL_POWER GND
J 0
(2600 4100);
PAINT GREEN (2600 4100);
DISPLAY INVISIBLE (2600 4100);
FORCEPROP 1 LAST BODY_TYPE PLUMBING
J 0
(2555 3907);
DISPLAY 0.340426 (2555 3907);
PAINT GREEN (2555 3907);
DISPLAY INVISIBLE (2555 3907);
FORCEPROP 1 LAST VOLTAGE 0.0V
J 0
(2555 3907);
DISPLAY 0.340426 (2555 3907);
PAINT SKYBLUE (2555 3907);
DISPLAY INVISIBLE (2555 3907);
FORCEPROP 1 LAST SIZE 1B
J 0
(2675 3900);
DISPLAY 2.382979 (2675 3900);
PAINT GREEN (2675 3900);
DISPLAY INVISIBLE (2675 3900);
FORCEPROP 2 LAST CDS_LIB mstr_symbols
J 0
(2600 3950);
PAINT ORANGE (2600 3950);
DISPLAY INVISIBLE (2600 3950);
FORCEPROP 1 LAST PATH I182
J 0
(2675 3950);
DISPLAY 0.872340 (2675 3950);
PAINT AQUA (2675 3950);
DISPLAY INVISIBLE (2675 3950);
FORCEADD 74CBTLV1G125..1
(3650 4400);
FORCEPROP 1 LAST MATERIAL IC
J 0
(3475 4620);
DISPLAY 0.617021 (3475 4620);
PAINT SKYBLUE (3475 4620);
FORCEPROP 1 LAST POWER_GROUP VCC=P3V3_STBY;GND=GND;
J 0
(3425 4200);
DISPLAY 0.617021 (3425 4200);
PAINT ORANGE (3425 4200);
FORCEPROP 0 LAST POP NOPOP
J 0
(3475 4150);
DISPLAY 0.638298 (3475 4150);
PAINT RED (3475 4150);
FORCEPROP 1 LAST PACK_TYPE SMLF
J 0
(3475 4570);
DISPLAY 0.617021 (3475 4570);
PAINT SKYBLUE (3475 4570);
FORCEPROP 1 LAST LOCATION U9A5
J 0
(3484 4531);
DISPLAY 0.617021 (3484 4531);
PAINT AQUA (3484 4531);
FORCEPROP 1 LAST PART_NUMBER C88177-001
J 0
(3485 4260);
DISPLAY 0.617021 (3485 4260);
PAINT BLUE (3485 4260);
FORCEPROP 2 LASTPIN (3900 4400) $PN 4
J 0
(3910 4410);
DISPLAY 0.617021 (3910 4410);
PAINT ORANGE (3910 4410);
FORCEPROP 2 LASTPIN (3400 4350) $PN 1
J 2
(3390 4360);
DISPLAY 0.617021 (3390 4360);
PAINT ORANGE (3390 4360);
FORCEPROP 2 LASTPIN (3400 4400) $PN 2
J 2
(3390 4410);
DISPLAY 0.617021 (3390 4410);
PAINT ORANGE (3390 4410);
FORCEPROP 1 LAST PATH I185
J 0
(3750 4520);
DISPLAY 0.872340 (3750 4520);
PAINT PINK (3750 4520);
DISPLAY INVISIBLE (3750 4520);
FORCEPROP 2 LAST SEC 1
J 0
(3475 4650);
DISPLAY 0.680851 (3475 4650);
PAINT MONO (3475 4650);
DISPLAY INVISIBLE (3475 4650);
FORCEPROP 2 LAST BOM_COST DEBUG
J 0
(3475 4725);
DISPLAY 1.021277 (3475 4725);
PAINT ORANGE (3475 4725);
DISPLAY INVISIBLE (3475 4725);
FORCEPROP 2 LAST SEC_TYPE SMLF
J 0
(3475 4650);
DISPLAY 1.021277 (3475 4650);
PAINT ORANGE (3475 4650);
DISPLAY INVISIBLE (3475 4650);
FORCEPROP 2 LAST ROOM DEBUG
J 0
(3475 4725);
DISPLAY 1.021277 (3475 4725);
PAINT ORANGE (3475 4725);
DISPLAY INVISIBLE (3475 4725);
FORCEPROP 2 LAST CDS_LIB mstr_ttl
J 0
(3650 4400);
PAINT ORANGE (3650 4400);
DISPLAY INVISIBLE (3650 4400);
FORCEADD GND..1
(3950 4300);
FORCEPROP 3 LASTPIN (3950 4350) SIG_NAME GND\g
J 0
(3960 4360);
DISPLAY 0.659574 (3960 4360);
PAINT MONO (3960 4360);
DISPLAY INVISIBLE (3960 4360);
FORCEPROP 1 LAST HDL_POWER GND
J 0
(3950 4450);
PAINT GREEN (3950 4450);
DISPLAY INVISIBLE (3950 4450);
FORCEPROP 1 LAST BODY_TYPE PLUMBING
J 0
(3905 4257);
DISPLAY 0.340426 (3905 4257);
PAINT GREEN (3905 4257);
DISPLAY INVISIBLE (3905 4257);
FORCEPROP 1 LAST PATH I186
J 0
(4025 4300);
DISPLAY 0.872340 (4025 4300);
PAINT AQUA (4025 4300);
DISPLAY INVISIBLE (4025 4300);
FORCEPROP 1 LAST SIZE 1B
J 0
(4025 4250);
DISPLAY 2.382979 (4025 4250);
PAINT GREEN (4025 4250);
DISPLAY INVISIBLE (4025 4250);
FORCEPROP 2 LAST CDS_LIB mstr_symbols
J 0
(3950 4300);
PAINT MONO (3950 4300);
DISPLAY INVISIBLE (3950 4300);
FORCEPROP 1 LAST VOLTAGE 0.0V
J 0
(3905 4257);
DISPLAY 0.340426 (3905 4257);
PAINT SKYBLUE (3905 4257);
DISPLAY INVISIBLE (3905 4257);
FORCEADD 74CBTLV1G125..1
(1600 2000);
FORCEPROP 1 LAST POWER_GROUP VCC=P3V3_STBY;GND=GND;
J 0
(1375 1800);
DISPLAY 0.617021 (1375 1800);
PAINT ORANGE (1375 1800);
FORCEPROP 0 LAST POP NOPOP
J 0
(1425 1750);
DISPLAY 0.638298 (1425 1750);
PAINT RED (1425 1750);
FORCEPROP 1 LAST PART_NUMBER C88177-001
J 0
(1435 1860);
DISPLAY 0.617021 (1435 1860);
PAINT BLUE (1435 1860);
FORCEPROP 2 LASTPIN (1350 1950) $PN 1
J 2
(1340 1960);
DISPLAY 0.617021 (1340 1960);
PAINT ORANGE (1340 1960);
FORCEPROP 2 LASTPIN (1350 2000) $PN 2
J 2
(1340 2010);
DISPLAY 0.617021 (1340 2010);
PAINT ORANGE (1340 2010);
FORCEPROP 1 LAST MATERIAL IC
J 0
(1425 2220);
DISPLAY 0.617021 (1425 2220);
PAINT SKYBLUE (1425 2220);
FORCEPROP 2 LASTPIN (1850 2000) $PN 4
J 0
(1860 2010);
DISPLAY 0.617021 (1860 2010);
PAINT ORANGE (1860 2010);
FORCEPROP 1 LAST PACK_TYPE SMLF
J 0
(1425 2170);
DISPLAY 0.617021 (1425 2170);
PAINT SKYBLUE (1425 2170);
FORCEPROP 1 LAST LOCATION U6M1
J 0
(1434 2131);
DISPLAY 0.617021 (1434 2131);
PAINT AQUA (1434 2131);
FORCEPROP 2 LAST SEC_TYPE SMLF
J 0
(1425 2250);
DISPLAY 1.021277 (1425 2250);
PAINT ORANGE (1425 2250);
DISPLAY INVISIBLE (1425 2250);
FORCEPROP 2 LAST SEC 1
J 0
(1425 2250);
DISPLAY 0.680851 (1425 2250);
PAINT MONO (1425 2250);
DISPLAY INVISIBLE (1425 2250);
FORCEPROP 2 LAST BOM_COST DEBUG
J 0
(1425 2325);
DISPLAY 1.021277 (1425 2325);
PAINT ORANGE (1425 2325);
DISPLAY INVISIBLE (1425 2325);
FORCEPROP 2 LAST ROOM DEBUG
J 0
(1425 2325);
DISPLAY 1.021277 (1425 2325);
PAINT ORANGE (1425 2325);
DISPLAY INVISIBLE (1425 2325);
FORCEPROP 1 LAST PATH I190
J 0
(1700 2120);
DISPLAY 0.872340 (1700 2120);
PAINT PINK (1700 2120);
DISPLAY INVISIBLE (1700 2120);
FORCEPROP 2 LAST CDS_LIB mstr_ttl
J 0
(1600 2000);
PAINT ORANGE (1600 2000);
DISPLAY INVISIBLE (1600 2000);
FORCEADD OFFPAGE..1
(450 1950);
FORCEPROP 2 LAST $XR0 55 
J 0
(229 1950);
DISPLAY 0.638298 (229 1950);
PAINT MONO (229 1950);
FORCEPROP 2 LAST $XR1 190 
J 0
(109 1950);
DISPLAY 0.638298 (109 1950);
PAINT MONO (109 1950);
FORCEPROP 1 LAST COMMENT_BODY TRUE
J 0
(575 1850);
DISPLAY 1.404255 (575 1850);
PAINT PEACH (575 1850);
DISPLAY INVISIBLE (575 1850);
FORCEPROP 1 LAST OFFPAGE TRUE
J 0
(775 1825);
DISPLAY 1.404255 (775 1825);
PAINT GREEN (775 1825);
DISPLAY INVISIBLE (775 1825);
FORCEPROP 2 LAST CDS_LIB mstr_standard
J 0
(450 1950);
PAINT ORANGE (450 1950);
DISPLAY INVISIBLE (450 1950);
FORCEPROP 2 LAST PATH I192
J 0
(500 2025);
DISPLAY 1.021277 (500 2025);
PAINT ORANGE (500 2025);
DISPLAY INVISIBLE (500 2025);
FORCEADD OFFPAGE..1
(2200 4350);
FORCEPROP 2 LAST $XR0 191 
J 0
(1948 4350);
DISPLAY 0.638298 (1948 4350);
PAINT MONO (1948 4350);
FORCEPROP 2 LAST $XR1 113 
J 0
(1828 4350);
DISPLAY 0.638298 (1828 4350);
PAINT MONO (1828 4350);
FORCEPROP 1 LAST COMMENT_BODY TRUE
J 0
(2325 4250);
DISPLAY 1.404255 (2325 4250);
PAINT PEACH (2325 4250);
DISPLAY INVISIBLE (2325 4250);
FORCEPROP 1 LAST OFFPAGE TRUE
J 0
(2525 4225);
DISPLAY 1.404255 (2525 4225);
PAINT GREEN (2525 4225);
DISPLAY INVISIBLE (2525 4225);
FORCEPROP 2 LAST CDS_LIB mstr_standard
J 0
(2200 4350);
PAINT ORANGE (2200 4350);
DISPLAY INVISIBLE (2200 4350);
FORCEPROP 2 LAST PATH I193
J 0
(2250 4425);
DISPLAY 1.021277 (2250 4425);
PAINT ORANGE (2250 4425);
DISPLAY INVISIBLE (2250 4425);
FORCEADD RES..2
R 2
(2450 2650);
FORCEPROP 1 LAST LOCATION R1M22
J 2
(2405 2775);
DISPLAY 0.617021 (2405 2775);
PAINT AQUA (2405 2775);
FORCEPROP 1 LASTPIN (2450 2550) $PN 2
J 2
(2445 2560);
DISPLAY 0.617021 (2445 2560);
PAINT ORANGE (2445 2560);
FORCEPROP 1 LAST VALUE 49.9
J 2
(2405 2725);
DISPLAY 0.617021 (2405 2725);
PAINT SKYBLUE (2405 2725);
FORCEPROP 1 LASTPIN (2450 2750) $PN 1
J 2
(2445 2712);
DISPLAY 0.617021 (2445 2712);
PAINT ORANGE (2445 2712);
FORCEPROP 1 LAST TOLERANCE 1%
J 2
(2405 2675);
DISPLAY 0.617021 (2405 2675);
PAINT SKYBLUE (2405 2675);
FORCEPROP 1 LAST PACK_TYPE 0402
J 2
(2410 2475);
DISPLAY 0.617021 (2410 2475);
PAINT SKYBLUE (2410 2475);
FORCEPROP 1 LAST PART_NUMBER G21796-047
J 2
(2410 2525);
DISPLAY 0.617021 (2410 2525);
PAINT BLUE (2410 2525);
FORCEPROP 1 LAST MATERIAL CHIP
J 2
(2410 2575);
DISPLAY 0.617021 (2410 2575);
PAINT SKYBLUE (2410 2575);
FORCEPROP 1 LAST WATTAGE 1/16W
J 2
(2410 2625);
DISPLAY 0.617021 (2410 2625);
PAINT SKYBLUE (2410 2625);
FORCEPROP 0 LAST POP NOPOP
J 0
(2275 2425);
DISPLAY 0.638298 (2275 2425);
PAINT RED (2275 2425);
FORCEPROP 2 LAST CDS_LIB mstr_discrete
J 2
(2450 2650);
PAINT ORANGE (2450 2650);
DISPLAY INVISIBLE (2450 2650);
FORCEPROP 2 LAST ROOM DEBUG
J 2
(2405 2815);
DISPLAY 1.276596 (2405 2815);
PAINT WHITE (2405 2815);
DISPLAY INVISIBLE (2405 2815);
FORCEPROP 2 LAST SEC 1
J 2
(2400 2875);
DISPLAY 0.680851 (2400 2875);
PAINT MONO (2400 2875);
DISPLAY INVISIBLE (2400 2875);
FORCEPROP 1 LAST PATH I195
J 2
(2400 2825);
DISPLAY 0.978723 (2400 2825);
PAINT WHITE (2400 2825);
DISPLAY INVISIBLE (2400 2825);
FORCEPROP 2 LAST SEC_TYPE 0402
J 2
(2400 2875);
DISPLAY 1.021277 (2400 2875);
PAINT ORANGE (2400 2875);
DISPLAY INVISIBLE (2400 2875);
FORCEADD 74CBTLV1G125..1
(1600 2825);
FORCEPROP 1 LAST POWER_GROUP VCC=P3V3_STBY;GND=GND;
J 0
(1375 2625);
DISPLAY 0.617021 (1375 2625);
PAINT ORANGE (1375 2625);
FORCEPROP 1 LAST MATERIAL IC
J 0
(1425 3045);
DISPLAY 0.617021 (1425 3045);
PAINT SKYBLUE (1425 3045);
FORCEPROP 2 LASTPIN (1850 2825) $PN 4
J 0
(1860 2835);
DISPLAY 0.617021 (1860 2835);
PAINT ORANGE (1860 2835);
FORCEPROP 0 LAST POP NOPOP
J 0
(1450 2575);
DISPLAY 0.638298 (1450 2575);
PAINT RED (1450 2575);
FORCEPROP 2 LASTPIN (1350 2775) $PN 1
J 2
(1340 2785);
DISPLAY 0.617021 (1340 2785);
PAINT ORANGE (1340 2785);
FORCEPROP 2 LASTPIN (1350 2825) $PN 2
J 2
(1340 2835);
DISPLAY 0.617021 (1340 2835);
PAINT ORANGE (1340 2835);
FORCEPROP 1 LAST PART_NUMBER C88177-001
J 0
(1435 2685);
DISPLAY 0.617021 (1435 2685);
PAINT BLUE (1435 2685);
FORCEPROP 1 LAST LOCATION U1M5
J 0
(1434 2956);
DISPLAY 0.617021 (1434 2956);
PAINT AQUA (1434 2956);
FORCEPROP 1 LAST PACK_TYPE SMLF
J 0
(1425 2995);
DISPLAY 0.617021 (1425 2995);
PAINT SKYBLUE (1425 2995);
FORCEPROP 2 LAST CDS_LIB mstr_ttl
J 0
(1600 2825);
PAINT ORANGE (1600 2825);
DISPLAY INVISIBLE (1600 2825);
FORCEPROP 1 LAST PATH I196
J 0
(1700 2945);
DISPLAY 0.872340 (1700 2945);
PAINT PINK (1700 2945);
DISPLAY INVISIBLE (1700 2945);
FORCEPROP 2 LAST SEC_TYPE SMLF
J 0
(1425 3075);
DISPLAY 1.021277 (1425 3075);
PAINT ORANGE (1425 3075);
DISPLAY INVISIBLE (1425 3075);
FORCEPROP 2 LAST BOM_COST DEBUG
J 0
(1425 3150);
DISPLAY 1.021277 (1425 3150);
PAINT ORANGE (1425 3150);
DISPLAY INVISIBLE (1425 3150);
FORCEPROP 2 LAST SEC 1
J 0
(1425 3075);
DISPLAY 0.680851 (1425 3075);
PAINT MONO (1425 3075);
DISPLAY INVISIBLE (1425 3075);
FORCEPROP 2 LAST ROOM DEBUG
J 0
(1425 3150);
DISPLAY 1.021277 (1425 3150);
PAINT ORANGE (1425 3150);
DISPLAY INVISIBLE (1425 3150);
FORCEADD OFFPAGE..1
(450 2775);
FORCEPROP 2 LAST $XR1 113 
J 0
(78 2775);
DISPLAY 0.638298 (78 2775);
PAINT MONO (78 2775);
FORCEPROP 2 LAST $XR0 191 
J 0
(198 2775);
DISPLAY 0.638298 (198 2775);
PAINT MONO (198 2775);
FORCEPROP 1 LAST COMMENT_BODY TRUE
J 0
(575 2675);
DISPLAY 1.404255 (575 2675);
PAINT PEACH (575 2675);
DISPLAY INVISIBLE (575 2675);
FORCEPROP 1 LAST OFFPAGE TRUE
J 0
(775 2650);
DISPLAY 1.404255 (775 2650);
PAINT GREEN (775 2650);
DISPLAY INVISIBLE (775 2650);
FORCEPROP 2 LAST CDS_LIB mstr_standard
J 0
(450 2775);
PAINT ORANGE (450 2775);
DISPLAY INVISIBLE (450 2775);
FORCEPROP 2 LAST PATH I197
J 0
(500 2850);
DISPLAY 1.021277 (500 2850);
PAINT ORANGE (500 2850);
DISPLAY INVISIBLE (500 2850);
FORCEADD RES..2
(1400 4225);
FORCEPROP 1 LAST PART_NUMBER G21796-026
J 0
(1440 4100);
DISPLAY 0.617021 (1440 4100);
PAINT BLUE (1440 4100);
FORCEPROP 1 LAST PACK_TYPE 0402
J 0
(1440 4050);
DISPLAY 0.617021 (1440 4050);
PAINT SKYBLUE (1440 4050);
FORCEPROP 1 LAST MATERIAL EMPTY
J 0
(1440 4150);
DISPLAY 0.617021 (1440 4150);
PAINT RED (1440 4150);
FORCEPROP 1 LASTPIN (1400 4325) $PN 1
J 0
(1405 4287);
DISPLAY 0.617021 (1405 4287);
PAINT ORANGE (1405 4287);
FORCEPROP 1 LASTPIN (1400 4125) $PN 2
J 0
(1405 4135);
DISPLAY 0.617021 (1405 4135);
PAINT ORANGE (1405 4135);
FORCEPROP 1 LAST LOCATION R1M23
J 0
(1445 4350);
DISPLAY 0.617021 (1445 4350);
PAINT AQUA (1445 4350);
FORCEPROP 1 LAST WATTAGE 1/16W
J 0
(1440 4200);
DISPLAY 0.617021 (1440 4200);
PAINT SKYBLUE (1440 4200);
FORCEPROP 1 LAST VALUE 1.00K
J 0
(1445 4300);
DISPLAY 0.617021 (1445 4300);
PAINT SKYBLUE (1445 4300);
FORCEPROP 1 LAST TOLERANCE 1%
J 0
(1445 4250);
DISPLAY 0.617021 (1445 4250);
PAINT SKYBLUE (1445 4250);
FORCEPROP 2 LAST CDS_LIB mstr_discrete
J 0
(1400 4225);
PAINT ORANGE (1400 4225);
DISPLAY INVISIBLE (1400 4225);
FORCEPROP 2 LAST ROOM DEBUG
J 0
(1450 4400);
DISPLAY 1.617021 (1450 4400);
PAINT WHITE (1450 4400);
DISPLAY INVISIBLE (1450 4400);
FORCEPROP 1 LAST PATH I199
J 0
(1450 4400);
DISPLAY 0.978723 (1450 4400);
PAINT WHITE (1450 4400);
DISPLAY INVISIBLE (1450 4400);
FORCEPROP 2 LAST SEC 1
J 0
(1450 4450);
DISPLAY 0.680851 (1450 4450);
PAINT MONO (1450 4450);
DISPLAY INVISIBLE (1450 4450);
FORCEPROP 2 LAST SEC_TYPE 0402
J 0
(1450 4450);
DISPLAY 1.021277 (1450 4450);
PAINT ORANGE (1450 4450);
DISPLAY INVISIBLE (1450 4450);
FORCEPROP 2 LAST BOM_COST DEBUG
J 0
(1450 4400);
DISPLAY 1.617021 (1450 4400);
PAINT WHITE (1450 4400);
DISPLAY INVISIBLE (1450 4400);
FORCEADD GND..1
(1400 3950);
FORCEPROP 3 LASTPIN (1400 4000) SIG_NAME GND\g
J 0
(1410 4010);
DISPLAY 0.659574 (1410 4010);
PAINT MONO (1410 4010);
DISPLAY INVISIBLE (1410 4010);
FORCEPROP 1 LAST HDL_POWER GND
J 0
(1400 4100);
PAINT GREEN (1400 4100);
DISPLAY INVISIBLE (1400 4100);
FORCEPROP 1 LAST BODY_TYPE PLUMBING
J 0
(1355 3907);
DISPLAY 0.340426 (1355 3907);
PAINT GREEN (1355 3907);
DISPLAY INVISIBLE (1355 3907);
FORCEPROP 1 LAST PATH I200
J 0
(1475 3950);
DISPLAY 0.872340 (1475 3950);
PAINT AQUA (1475 3950);
DISPLAY INVISIBLE (1475 3950);
FORCEPROP 2 LAST CDS_LIB mstr_symbols
J 0
(1400 3950);
PAINT ORANGE (1400 3950);
DISPLAY INVISIBLE (1400 3950);
FORCEPROP 1 LAST VOLTAGE 0.0V
J 0
(1355 3907);
DISPLAY 0.340426 (1355 3907);
PAINT SKYBLUE (1355 3907);
DISPLAY INVISIBLE (1355 3907);
FORCEPROP 1 LAST SIZE 1B
J 0
(1475 3900);
DISPLAY 2.382979 (1475 3900);
PAINT GREEN (1475 3900);
DISPLAY INVISIBLE (1475 3900);
FORCEADD VCC_CORE..1
(3575 1275);
FORCEPROP 3 LASTPIN (3575 1225) SIG_NAME P1V8_MCP_CPU0\g
J 0
(3585 1235);
DISPLAY 0.659574 (3585 1235);
PAINT MONO (3585 1235);
DISPLAY INVISIBLE (3585 1235);
FORCEPROP 1 LAST HDL_POWER P1V8_MCP_CPU0
J 1
(3575 1325);
DISPLAY 0.617021 (3575 1325);
PAINT GREEN (3575 1325);
FORCEPROP 2 LAST CDS_LIB mstr_symbols
J 0
(3575 1275);
PAINT ORANGE (3575 1275);
DISPLAY INVISIBLE (3575 1275);
FORCEPROP 1 LAST PATH I201
J 0
(3625 1300);
DISPLAY 0.872340 (3625 1300);
PAINT AQUA (3625 1300);
DISPLAY INVISIBLE (3625 1300);
FORCEADD RES..2
(3175 1025);
FORCEPROP 1 LAST LOCATION R1M19
J 0
(3220 1150);
DISPLAY 0.617021 (3220 1150);
PAINT AQUA (3220 1150);
FORCEPROP 1 LAST WATTAGE 1/16W
J 0
(3215 1000);
DISPLAY 0.617021 (3215 1000);
PAINT SKYBLUE (3215 1000);
FORCEPROP 1 LAST MATERIAL CHIP
J 0
(3215 950);
DISPLAY 0.617021 (3215 950);
PAINT SKYBLUE (3215 950);
FORCEPROP 1 LASTPIN (3175 1125) $PN 1
J 0
(3180 1087);
DISPLAY 0.617021 (3180 1087);
PAINT ORANGE (3180 1087);
FORCEPROP 1 LAST VALUE 1.00K
J 0
(3220 1100);
DISPLAY 0.617021 (3220 1100);
PAINT SKYBLUE (3220 1100);
FORCEPROP 1 LAST PACK_TYPE 0402
J 0
(3215 850);
DISPLAY 0.617021 (3215 850);
PAINT SKYBLUE (3215 850);
FORCEPROP 1 LAST TOLERANCE 1%
J 0
(3220 1050);
DISPLAY 0.617021 (3220 1050);
PAINT SKYBLUE (3220 1050);
FORCEPROP 1 LASTPIN (3175 925) $PN 2
J 0
(3180 935);
DISPLAY 0.617021 (3180 935);
PAINT ORANGE (3180 935);
FORCEPROP 0 LAST GROUP MCP
J 0
(3200 800);
DISPLAY 0.638298 (3200 800);
PAINT BROWN (3200 800);
DISPLAY BOTH (3200 800);
FORCEPROP 1 LAST PART_NUMBER G21796-026
J 0
(3215 900);
DISPLAY 0.617021 (3215 900);
PAINT BLUE (3215 900);
FORCEPROP 2 LAST SEC 1
J 0
(3225 1250);
DISPLAY 0.680851 (3225 1250);
PAINT MONO (3225 1250);
DISPLAY INVISIBLE (3225 1250);
FORCEPROP 2 LAST BOM_COST DEBUG
J 0
(3225 1200);
DISPLAY 1.617021 (3225 1200);
PAINT WHITE (3225 1200);
DISPLAY INVISIBLE (3225 1200);
FORCEPROP 2 LAST SEC_TYPE 0402
J 0
(3225 1250);
DISPLAY 1.021277 (3225 1250);
PAINT ORANGE (3225 1250);
DISPLAY INVISIBLE (3225 1250);
FORCEPROP 2 LAST ROOM DEBUG
J 0
(3225 1200);
DISPLAY 1.617021 (3225 1200);
PAINT WHITE (3225 1200);
DISPLAY INVISIBLE (3225 1200);
FORCEPROP 1 LAST PATH I202
J 0
(3225 1200);
DISPLAY 0.978723 (3225 1200);
PAINT WHITE (3225 1200);
DISPLAY INVISIBLE (3225 1200);
FORCEPROP 2 LAST CDS_LIB mstr_discrete
J 0
(3175 1025);
PAINT ORANGE (3175 1025);
DISPLAY INVISIBLE (3175 1025);
FORCEADD RES..2
(3425 1025);
FORCEPROP 1 LAST LOCATION R9B12
J 0
(3470 1150);
DISPLAY 0.617021 (3470 1150);
PAINT AQUA (3470 1150);
FORCEPROP 1 LAST PART_NUMBER G21796-026
J 0
(3465 900);
DISPLAY 0.617021 (3465 900);
PAINT BLUE (3465 900);
FORCEPROP 1 LAST PACK_TYPE 0402
J 0
(3465 850);
DISPLAY 0.617021 (3465 850);
PAINT SKYBLUE (3465 850);
FORCEPROP 0 LAST GROUP MCP
J 0
(3475 800);
DISPLAY 0.638298 (3475 800);
PAINT BROWN (3475 800);
DISPLAY BOTH (3475 800);
FORCEPROP 1 LAST WATTAGE 1/16W
J 0
(3465 1000);
DISPLAY 0.617021 (3465 1000);
PAINT SKYBLUE (3465 1000);
FORCEPROP 1 LASTPIN (3425 1125) $PN 1
J 0
(3430 1087);
DISPLAY 0.617021 (3430 1087);
PAINT ORANGE (3430 1087);
FORCEPROP 1 LAST MATERIAL CHIP
J 0
(3465 950);
DISPLAY 0.617021 (3465 950);
PAINT SKYBLUE (3465 950);
FORCEPROP 1 LASTPIN (3425 925) $PN 2
J 0
(3430 935);
DISPLAY 0.617021 (3430 935);
PAINT ORANGE (3430 935);
FORCEPROP 1 LAST TOLERANCE 1%
J 0
(3470 1050);
DISPLAY 0.617021 (3470 1050);
PAINT SKYBLUE (3470 1050);
FORCEPROP 1 LAST VALUE 1.00K
J 0
(3470 1100);
DISPLAY 0.617021 (3470 1100);
PAINT SKYBLUE (3470 1100);
FORCEPROP 2 LAST ROOM DEBUG
J 0
(3475 1200);
DISPLAY 1.617021 (3475 1200);
PAINT WHITE (3475 1200);
DISPLAY INVISIBLE (3475 1200);
FORCEPROP 2 LAST SEC 1
J 0
(3475 1250);
DISPLAY 0.680851 (3475 1250);
PAINT MONO (3475 1250);
DISPLAY INVISIBLE (3475 1250);
FORCEPROP 2 LAST SEC_TYPE 0402
J 0
(3475 1250);
DISPLAY 1.021277 (3475 1250);
PAINT ORANGE (3475 1250);
DISPLAY INVISIBLE (3475 1250);
FORCEPROP 2 LAST BOM_COST DEBUG
J 0
(3475 1200);
DISPLAY 1.617021 (3475 1200);
PAINT WHITE (3475 1200);
DISPLAY INVISIBLE (3475 1200);
FORCEPROP 1 LAST PATH I203
J 0
(3475 1200);
DISPLAY 0.978723 (3475 1200);
PAINT WHITE (3475 1200);
DISPLAY INVISIBLE (3475 1200);
FORCEPROP 2 LAST CDS_LIB mstr_discrete
J 0
(3425 1025);
PAINT ORANGE (3425 1025);
DISPLAY INVISIBLE (3425 1025);
FORCEADD RES..2
(2925 1025);
FORCEPROP 1 LAST PART_NUMBER G21796-026
J 0
(2965 900);
DISPLAY 0.617021 (2965 900);
PAINT BLUE (2965 900);
FORCEPROP 1 LAST PACK_TYPE 0402
J 0
(2965 850);
DISPLAY 0.617021 (2965 850);
PAINT SKYBLUE (2965 850);
FORCEPROP 0 LAST POP NOPOP
J 0
(2975 800);
DISPLAY 0.638298 (2975 800);
PAINT RED (2975 800);
FORCEPROP 1 LAST WATTAGE 1/16W
J 0
(2965 1000);
DISPLAY 0.617021 (2965 1000);
PAINT SKYBLUE (2965 1000);
FORCEPROP 1 LAST MATERIAL CHIP
J 0
(2965 950);
DISPLAY 0.617021 (2965 950);
PAINT SKYBLUE (2965 950);
FORCEPROP 1 LAST LOCATION R1M20
J 0
(2970 1150);
DISPLAY 0.617021 (2970 1150);
PAINT AQUA (2970 1150);
FORCEPROP 1 LAST VALUE 1.00K
J 0
(2970 1100);
DISPLAY 0.617021 (2970 1100);
PAINT SKYBLUE (2970 1100);
FORCEPROP 1 LAST TOLERANCE 1%
J 0
(2970 1050);
DISPLAY 0.617021 (2970 1050);
PAINT SKYBLUE (2970 1050);
FORCEPROP 1 LASTPIN (2925 1125) $PN 1
J 0
(2930 1087);
DISPLAY 0.617021 (2930 1087);
PAINT ORANGE (2930 1087);
FORCEPROP 1 LASTPIN (2925 925) $PN 2
J 0
(2930 935);
DISPLAY 0.617021 (2930 935);
PAINT ORANGE (2930 935);
FORCEPROP 2 LAST ROOM DEBUG
J 0
(2975 1200);
DISPLAY 1.617021 (2975 1200);
PAINT WHITE (2975 1200);
DISPLAY INVISIBLE (2975 1200);
FORCEPROP 2 LAST SEC 1
J 0
(2975 1250);
DISPLAY 0.680851 (2975 1250);
PAINT MONO (2975 1250);
DISPLAY INVISIBLE (2975 1250);
FORCEPROP 2 LAST SEC_TYPE 0402
J 0
(2975 1250);
DISPLAY 1.021277 (2975 1250);
PAINT ORANGE (2975 1250);
DISPLAY INVISIBLE (2975 1250);
FORCEPROP 2 LAST BOM_COST DEBUG
J 0
(2975 1200);
DISPLAY 1.617021 (2975 1200);
PAINT WHITE (2975 1200);
DISPLAY INVISIBLE (2975 1200);
FORCEPROP 1 LAST PATH I204
J 0
(2975 1200);
DISPLAY 0.978723 (2975 1200);
PAINT WHITE (2975 1200);
DISPLAY INVISIBLE (2975 1200);
FORCEPROP 2 LAST CDS_LIB mstr_discrete
J 0
(2925 1025);
PAINT ORANGE (2925 1025);
DISPLAY INVISIBLE (2925 1025);
FORCEADD RES..2
(3675 1025);
FORCEPROP 1 LAST LOCATION R1M21
J 0
(3720 1150);
DISPLAY 0.617021 (3720 1150);
PAINT AQUA (3720 1150);
FORCEPROP 1 LAST WATTAGE 1/16W
J 0
(3715 1000);
DISPLAY 0.617021 (3715 1000);
PAINT SKYBLUE (3715 1000);
FORCEPROP 0 LAST GROUP MCP
J 0
(3725 800);
DISPLAY 0.638298 (3725 800);
PAINT BROWN (3725 800);
DISPLAY BOTH (3725 800);
FORCEPROP 1 LAST MATERIAL CHIP
J 0
(3715 950);
DISPLAY 0.617021 (3715 950);
PAINT SKYBLUE (3715 950);
FORCEPROP 1 LAST PART_NUMBER G21796-026
J 0
(3715 900);
DISPLAY 0.617021 (3715 900);
PAINT BLUE (3715 900);
FORCEPROP 1 LAST VALUE 1.00K
J 0
(3720 1100);
DISPLAY 0.617021 (3720 1100);
PAINT SKYBLUE (3720 1100);
FORCEPROP 1 LAST TOLERANCE 1%
J 0
(3720 1050);
DISPLAY 0.617021 (3720 1050);
PAINT SKYBLUE (3720 1050);
FORCEPROP 1 LASTPIN (3675 1125) $PN 1
J 0
(3680 1087);
DISPLAY 0.617021 (3680 1087);
PAINT ORANGE (3680 1087);
FORCEPROP 1 LASTPIN (3675 925) $PN 2
J 0
(3680 935);
DISPLAY 0.617021 (3680 935);
PAINT ORANGE (3680 935);
FORCEPROP 1 LAST PACK_TYPE 0402
J 0
(3715 850);
DISPLAY 0.617021 (3715 850);
PAINT SKYBLUE (3715 850);
FORCEPROP 2 LAST BOM_COST DEBUG
J 0
(3725 1200);
DISPLAY 1.617021 (3725 1200);
PAINT WHITE (3725 1200);
DISPLAY INVISIBLE (3725 1200);
FORCEPROP 2 LAST SEC_TYPE 0402
J 0
(3725 1250);
DISPLAY 1.021277 (3725 1250);
PAINT ORANGE (3725 1250);
DISPLAY INVISIBLE (3725 1250);
FORCEPROP 2 LAST SEC 1
J 0
(3725 1250);
DISPLAY 0.680851 (3725 1250);
PAINT MONO (3725 1250);
DISPLAY INVISIBLE (3725 1250);
FORCEPROP 2 LAST ROOM DEBUG
J 0
(3725 1200);
DISPLAY 1.617021 (3725 1200);
PAINT WHITE (3725 1200);
DISPLAY INVISIBLE (3725 1200);
FORCEPROP 1 LAST PATH I205
J 0
(3725 1200);
DISPLAY 0.978723 (3725 1200);
PAINT WHITE (3725 1200);
DISPLAY INVISIBLE (3725 1200);
FORCEPROP 2 LAST CDS_LIB mstr_discrete
J 0
(3675 1025);
PAINT ORANGE (3675 1025);
DISPLAY INVISIBLE (3675 1025);
FORCEADD 74CBTLV1G125..1
(1625 3375);
FORCEPROP 1 LAST LOCATION U4R1
J 0
(1459 3506);
DISPLAY 0.617021 (1459 3506);
PAINT AQUA (1459 3506);
FORCEPROP 2 LASTPIN (1375 3375) $PN 2
J 2
(1365 3385);
DISPLAY 0.617021 (1365 3385);
PAINT ORANGE (1365 3385);
FORCEPROP 1 LAST POWER_GROUP VCC=P3V3_STBY;GND=GND;
J 0
(1400 3175);
DISPLAY 0.617021 (1400 3175);
PAINT ORANGE (1400 3175);
FORCEPROP 0 LAST POP NOPOP
J 0
(1450 3125);
DISPLAY 0.638298 (1450 3125);
PAINT RED (1450 3125);
FORCEPROP 2 LASTPIN (1875 3375) $PN 4
J 0
(1885 3385);
DISPLAY 0.617021 (1885 3385);
PAINT ORANGE (1885 3385);
FORCEPROP 2 LASTPIN (1375 3325) $PN 1
J 2
(1365 3335);
DISPLAY 0.617021 (1365 3335);
PAINT ORANGE (1365 3335);
FORCEPROP 1 LAST PART_NUMBER C88177-001
J 0
(1460 3235);
DISPLAY 0.617021 (1460 3235);
PAINT BLUE (1460 3235);
FORCEPROP 1 LAST PACK_TYPE SMLF
J 0
(1450 3545);
DISPLAY 0.617021 (1450 3545);
PAINT SKYBLUE (1450 3545);
FORCEPROP 1 LAST MATERIAL IC
J 0
(1450 3595);
DISPLAY 0.617021 (1450 3595);
PAINT SKYBLUE (1450 3595);
FORCEPROP 2 LAST SEC_TYPE SMLF
J 0
(1450 3625);
DISPLAY 1.021277 (1450 3625);
PAINT ORANGE (1450 3625);
DISPLAY INVISIBLE (1450 3625);
FORCEPROP 2 LAST BOM_COST DEBUG
J 0
(1450 3700);
DISPLAY 1.021277 (1450 3700);
PAINT ORANGE (1450 3700);
DISPLAY INVISIBLE (1450 3700);
FORCEPROP 2 LAST SEC 1
J 0
(1450 3625);
DISPLAY 0.680851 (1450 3625);
PAINT MONO (1450 3625);
DISPLAY INVISIBLE (1450 3625);
FORCEPROP 2 LAST ROOM DEBUG
J 0
(1450 3700);
DISPLAY 1.021277 (1450 3700);
PAINT ORANGE (1450 3700);
DISPLAY INVISIBLE (1450 3700);
FORCEPROP 1 LAST PATH I206
J 0
(1725 3495);
DISPLAY 0.872340 (1725 3495);
PAINT PINK (1725 3495);
DISPLAY INVISIBLE (1725 3495);
FORCEPROP 2 LAST CDS_LIB mstr_ttl
J 0
(1625 3375);
PAINT ORANGE (1625 3375);
DISPLAY INVISIBLE (1625 3375);
FORCEADD OFFPAGE..1
(2425 800);
FORCEPROP 2 LAST $XR1 29 
J 0
(2083 800);
DISPLAY 0.638298 (2083 800);
PAINT MONO (2083 800);
FORCEPROP 2 LAST $XR2 63 
J 0
(1993 800);
DISPLAY 0.638298 (1993 800);
PAINT MONO (1993 800);
FORCEPROP 2 LAST $XR0 113 
J 0
(2173 800);
DISPLAY 0.638298 (2173 800);
PAINT MONO (2173 800);
FORCEPROP 1 LAST COMMENT_BODY TRUE
J 0
(2550 700);
DISPLAY 1.404255 (2550 700);
PAINT PEACH (2550 700);
DISPLAY INVISIBLE (2550 700);
FORCEPROP 1 LAST OFFPAGE TRUE
J 0
(2750 675);
DISPLAY 1.404255 (2750 675);
PAINT GREEN (2750 675);
DISPLAY INVISIBLE (2750 675);
FORCEPROP 2 LAST CDS_LIB mstr_standard
J 0
(2425 800);
PAINT MONO (2425 800);
DISPLAY INVISIBLE (2425 800);
FORCEPROP 2 LAST PATH I212
J 0
(2150 850);
DISPLAY 1.021277 (2150 850);
PAINT ORANGE (2150 850);
DISPLAY INVISIBLE (2150 850);
FORCEADD OFFPAGE..1
(2425 700);
FORCEPROP 2 LAST $XR0 113 
J 0
(2173 700);
DISPLAY 0.638298 (2173 700);
PAINT MONO (2173 700);
FORCEPROP 2 LAST $XR1 29 
J 0
(2083 700);
DISPLAY 0.638298 (2083 700);
PAINT MONO (2083 700);
FORCEPROP 2 LAST $XR2 63 
J 0
(1993 700);
DISPLAY 0.638298 (1993 700);
PAINT MONO (1993 700);
FORCEPROP 1 LAST COMMENT_BODY TRUE
J 0
(2550 600);
DISPLAY 1.404255 (2550 600);
PAINT PEACH (2550 600);
DISPLAY INVISIBLE (2550 600);
FORCEPROP 1 LAST OFFPAGE TRUE
J 0
(2750 575);
DISPLAY 1.404255 (2750 575);
PAINT GREEN (2750 575);
DISPLAY INVISIBLE (2750 575);
FORCEPROP 2 LAST CDS_LIB mstr_standard
J 0
(2425 700);
PAINT MONO (2425 700);
DISPLAY INVISIBLE (2425 700);
FORCEPROP 2 LAST PATH I213
J 0
(2150 750);
DISPLAY 1.021277 (2150 750);
PAINT ORANGE (2150 750);
DISPLAY INVISIBLE (2150 750);
FORCEADD OFFPAGE..1
(2425 750);
FORCEPROP 2 LAST $XR0 113 
J 0
(2173 750);
DISPLAY 0.638298 (2173 750);
PAINT MONO (2173 750);
FORCEPROP 1 LAST COMMENT_BODY TRUE
J 0
(2550 650);
DISPLAY 1.404255 (2550 650);
PAINT PEACH (2550 650);
DISPLAY INVISIBLE (2550 650);
FORCEPROP 1 LAST OFFPAGE TRUE
J 0
(2750 625);
DISPLAY 1.404255 (2750 625);
PAINT GREEN (2750 625);
DISPLAY INVISIBLE (2750 625);
FORCEPROP 2 LAST CDS_LIB mstr_standard
J 0
(2425 750);
DISPLAY 2.212766 (2425 750);
PAINT ORANGE (2425 750);
DISPLAY INVISIBLE (2425 750);
FORCEPROP 2 LAST PATH I214
J 0
(2150 800);
DISPLAY 1.021277 (2150 800);
PAINT ORANGE (2150 800);
DISPLAY INVISIBLE (2150 800);
FORCEADD OFFPAGE..1
(2425 850);
FORCEPROP 2 LAST $XR0 113 
J 0
(2173 850);
DISPLAY 0.638298 (2173 850);
PAINT MONO (2173 850);
FORCEPROP 1 LAST COMMENT_BODY TRUE
J 0
(2550 750);
DISPLAY 1.404255 (2550 750);
PAINT PEACH (2550 750);
DISPLAY INVISIBLE (2550 750);
FORCEPROP 1 LAST OFFPAGE TRUE
J 0
(2750 725);
DISPLAY 1.404255 (2750 725);
PAINT GREEN (2750 725);
DISPLAY INVISIBLE (2750 725);
FORCEPROP 2 LAST CDS_LIB mstr_standard
J 0
(2425 850);
DISPLAY 2.212766 (2425 850);
PAINT ORANGE (2425 850);
DISPLAY INVISIBLE (2425 850);
FORCEPROP 2 LAST PATH I215
J 0
(2150 900);
DISPLAY 1.021277 (2150 900);
PAINT ORANGE (2150 900);
DISPLAY INVISIBLE (2150 900);
FORCEADD VCC_CORE..1
(900 2100);
FORCEPROP 3 LASTPIN (900 2050) SIG_NAME P1V8_MCP_CPU1\g
J 0
(910 2060);
DISPLAY 0.659574 (910 2060);
PAINT MONO (910 2060);
DISPLAY INVISIBLE (910 2060);
FORCEPROP 1 LAST HDL_POWER P1V8_MCP_CPU1
J 1
(900 2150);
DISPLAY 0.617021 (900 2150);
PAINT GREEN (900 2150);
FORCEPROP 0 LAST VOLTAGE 1.8
J 0
(900 2250);
DISPLAY 1.021277 (900 2250);
PAINT SKYBLUE (900 2250);
DISPLAY INVISIBLE (900 2250);
FORCEPROP 1 LAST PATH I236
J 0
(950 2125);
DISPLAY 0.872340 (950 2125);
PAINT AQUA (950 2125);
DISPLAY INVISIBLE (950 2125);
FORCEPROP 2 LAST CDS_LIB mstr_symbols
J 0
(900 2100);
PAINT ORANGE (900 2100);
DISPLAY INVISIBLE (900 2100);
FORCEADD OFFPAGE..1
(450 3325);
FORCEPROP 2 LAST $XR1 190 
J 0
(109 3325);
DISPLAY 0.638298 (109 3325);
PAINT MONO (109 3325);
FORCEPROP 2 LAST $XR0 21 
J 0
(229 3325);
DISPLAY 0.638298 (229 3325);
PAINT MONO (229 3325);
FORCEPROP 1 LAST COMMENT_BODY TRUE
J 0
(575 3225);
DISPLAY 1.404255 (575 3225);
PAINT PEACH (575 3225);
DISPLAY INVISIBLE (575 3225);
FORCEPROP 1 LAST OFFPAGE TRUE
J 0
(775 3200);
DISPLAY 1.404255 (775 3200);
PAINT GREEN (775 3200);
DISPLAY INVISIBLE (775 3200);
FORCEPROP 2 LAST CDS_LIB mstr_standard
J 0
(450 3325);
PAINT ORANGE (450 3325);
DISPLAY INVISIBLE (450 3325);
FORCEPROP 2 LAST PATH I238
J 0
(500 3400);
DISPLAY 1.021277 (500 3400);
PAINT ORANGE (500 3400);
DISPLAY INVISIBLE (500 3400);
FORCEADD RES..1
(-2600 4625);
FORCEPROP 1 LAST LOCATION R9B11
J 0
(-2650 4675);
DISPLAY 0.617021 (-2650 4675);
PAINT AQUA (-2650 4675);
FORCEPROP 1 LASTPIN (-2500 4625) $PN 2
J 0
(-2538 4637);
DISPLAY 0.617021 (-2538 4637);
PAINT ORANGE (-2538 4637);
FORCEPROP 1 LASTPIN (-2700 4625) $PN 1
J 0
(-2688 4637);
DISPLAY 0.617021 (-2688 4637);
PAINT ORANGE (-2688 4637);
FORCEPROP 1 LAST PACK_TYPE 0402
J 0
(-2725 4525);
DISPLAY 0.617021 (-2725 4525);
PAINT SKYBLUE (-2725 4525);
FORCEPROP 1 LAST MATERIAL CHIP
J 0
(-2500 4575);
DISPLAY 0.617021 (-2500 4575);
PAINT SKYBLUE (-2500 4575);
FORCEPROP 1 LAST VALUE 0.0
J 2
(-2725 4575);
DISPLAY 0.617021 (-2725 4575);
PAINT SKYBLUE (-2725 4575);
FORCEPROP 1 LAST TOLERANCE 5%
J 0
(-2700 4575);
DISPLAY 0.617021 (-2700 4575);
PAINT SKYBLUE (-2700 4575);
FORCEPROP 1 LAST WATTAGE 1/16W
J 2
(-2525 4575);
DISPLAY 0.617021 (-2525 4575);
PAINT SKYBLUE (-2525 4575);
FORCEPROP 1 LAST PART_NUMBER G21497-005
J 0
(-2625 4525);
DISPLAY 0.617021 (-2625 4525);
PAINT BLUE (-2625 4525);
FORCEPROP 0 LAST GROUP MCP
J 0
(-2400 4525);
DISPLAY 0.638298 (-2400 4525);
PAINT BROWN (-2400 4525);
DISPLAY BOTH (-2400 4525);
FORCEPROP 1 LAST PATH I239
J 0
(-2650 4775);
DISPLAY 0.978723 (-2650 4775);
PAINT WHITE (-2650 4775);
DISPLAY INVISIBLE (-2650 4775);
FORCEPROP 2 LAST SEC_TYPE 0402
J 0
(-2650 4825);
DISPLAY 1.021277 (-2650 4825);
PAINT ORANGE (-2650 4825);
DISPLAY INVISIBLE (-2650 4825);
FORCEPROP 2 LAST CDS_LIB mstr_discrete
J 0
(-2600 4625);
PAINT ORANGE (-2600 4625);
DISPLAY INVISIBLE (-2600 4625);
FORCEPROP 2 LAST SEC 1
J 0
(-2650 4825);
DISPLAY 0.680851 (-2650 4825);
PAINT MONO (-2650 4825);
DISPLAY INVISIBLE (-2650 4825);
FORCEADD RES..1
(-2600 4375);
FORCEPROP 1 LAST VALUE 0.0
J 2
(-2725 4325);
DISPLAY 0.617021 (-2725 4325);
PAINT SKYBLUE (-2725 4325);
FORCEPROP 1 LAST TOLERANCE 5%
J 0
(-2700 4325);
DISPLAY 0.617021 (-2700 4325);
PAINT SKYBLUE (-2700 4325);
FORCEPROP 1 LAST PACK_TYPE 0402
J 0
(-2725 4275);
DISPLAY 0.617021 (-2725 4275);
PAINT SKYBLUE (-2725 4275);
FORCEPROP 1 LASTPIN (-2700 4375) $PN 1
J 0
(-2688 4387);
DISPLAY 0.617021 (-2688 4387);
PAINT ORANGE (-2688 4387);
FORCEPROP 1 LASTPIN (-2500 4375) $PN 2
J 0
(-2538 4387);
DISPLAY 0.617021 (-2538 4387);
PAINT ORANGE (-2538 4387);
FORCEPROP 1 LAST WATTAGE 1/16W
J 2
(-2525 4325);
DISPLAY 0.617021 (-2525 4325);
PAINT SKYBLUE (-2525 4325);
FORCEPROP 1 LAST MATERIAL CHIP
J 0
(-2500 4325);
DISPLAY 0.617021 (-2500 4325);
PAINT SKYBLUE (-2500 4325);
FORCEPROP 1 LAST PART_NUMBER G21497-005
J 0
(-2625 4275);
DISPLAY 0.617021 (-2625 4275);
PAINT BLUE (-2625 4275);
FORCEPROP 0 LAST GROUP MCP
J 0
(-2400 4275);
DISPLAY 0.638298 (-2400 4275);
PAINT BROWN (-2400 4275);
DISPLAY BOTH (-2400 4275);
FORCEPROP 1 LAST LOCATION R9B13
J 0
(-2650 4425);
DISPLAY 0.617021 (-2650 4425);
PAINT AQUA (-2650 4425);
FORCEPROP 2 LAST CDS_LIB mstr_discrete
J 0
(-2600 4375);
PAINT ORANGE (-2600 4375);
DISPLAY INVISIBLE (-2600 4375);
FORCEPROP 2 LAST SEC 1
J 0
(-2650 4575);
DISPLAY 0.680851 (-2650 4575);
PAINT MONO (-2650 4575);
DISPLAY INVISIBLE (-2650 4575);
FORCEPROP 1 LAST PATH I240
J 0
(-2650 4525);
DISPLAY 0.978723 (-2650 4525);
PAINT WHITE (-2650 4525);
DISPLAY INVISIBLE (-2650 4525);
FORCEPROP 2 LAST SEC_TYPE 0402
J 0
(-2650 4575);
DISPLAY 1.021277 (-2650 4575);
PAINT ORANGE (-2650 4575);
DISPLAY INVISIBLE (-2650 4575);
FORCEADD VCC_CORE..1
(900 3475);
FORCEPROP 3 LASTPIN (900 3425) SIG_NAME P1V8_MCP_CPU0\g
J 0
(910 3435);
DISPLAY 0.659574 (910 3435);
PAINT MONO (910 3435);
DISPLAY INVISIBLE (910 3435);
FORCEPROP 1 LAST HDL_POWER P1V8_MCP_CPU0
J 1
(900 3525);
DISPLAY 0.617021 (900 3525);
PAINT GREEN (900 3525);
FORCEPROP 1 LAST PATH I241
J 0
(950 3500);
DISPLAY 0.872340 (950 3500);
PAINT AQUA (950 3500);
DISPLAY INVISIBLE (950 3500);
FORCEPROP 2 LAST CDS_LIB mstr_symbols
J 0
(900 3475);
PAINT ORANGE (900 3475);
DISPLAY INVISIBLE (900 3475);
FORCEADD OFFPAGE..2
(2925 3025);
FORCEPROP 2 LAST $XR1 113 
J 0
(3204 3025);
DISPLAY 0.638298 (3204 3025);
PAINT MONO (3204 3025);
FORCEPROP 2 LAST $XR0 29 
J 0
(3114 3025);
DISPLAY 0.638298 (3114 3025);
PAINT MONO (3114 3025);
FORCEPROP 1 LAST COMMENT_BODY TRUE
J 0
(2880 2930);
DISPLAY 0.872340 (2880 2930);
PAINT GREEN (2880 2930);
DISPLAY INVISIBLE (2880 2930);
FORCEPROP 1 LAST OFFPAGE TRUE
J 0
(3250 2900);
DISPLAY 0.872340 (3250 2900);
PAINT GREEN (3250 2900);
DISPLAY INVISIBLE (3250 2900);
FORCEPROP 2 LAST CDS_LIB mstr_standard
J 0
(2925 3025);
PAINT ORANGE (2925 3025);
DISPLAY INVISIBLE (2925 3025);
FORCEPROP 2 LAST PATH I242
J 0
(3100 3100);
DISPLAY 1.021277 (3100 3100);
PAINT ORANGE (3100 3100);
DISPLAY INVISIBLE (3100 3100);
FORCEADD OFFPAGE..2
(2925 2475);
FORCEPROP 2 LAST $XR0 113 
J 0
(3114 2475);
DISPLAY 0.638298 (3114 2475);
PAINT MONO (3114 2475);
FORCEPROP 2 LAST $XR1 29 
J 0
(3234 2475);
DISPLAY 0.638298 (3234 2475);
PAINT MONO (3234 2475);
FORCEPROP 2 LAST $XR2 63 
J 0
(3324 2475);
DISPLAY 0.638298 (3324 2475);
PAINT MONO (3324 2475);
FORCEPROP 1 LAST COMMENT_BODY TRUE
J 0
(2880 2380);
DISPLAY 0.872340 (2880 2380);
PAINT GREEN (2880 2380);
DISPLAY INVISIBLE (2880 2380);
FORCEPROP 1 LAST OFFPAGE TRUE
J 0
(3250 2350);
DISPLAY 0.872340 (3250 2350);
PAINT GREEN (3250 2350);
DISPLAY INVISIBLE (3250 2350);
FORCEPROP 2 LAST CDS_LIB mstr_standard
J 0
(2925 2475);
PAINT ORANGE (2925 2475);
DISPLAY INVISIBLE (2925 2475);
FORCEPROP 2 LAST PATH I243
J 0
(3100 2550);
DISPLAY 1.021277 (3100 2550);
PAINT ORANGE (3100 2550);
DISPLAY INVISIBLE (3100 2550);
FORCEADD OFFPAGE..2
(2950 1650);
FORCEPROP 2 LAST $XR0 113 
J 0
(3139 1650);
DISPLAY 0.638298 (3139 1650);
PAINT MONO (3139 1650);
FORCEPROP 2 LAST $XR1 63 
J 0
(3259 1650);
DISPLAY 0.638298 (3259 1650);
PAINT MONO (3259 1650);
FORCEPROP 1 LAST COMMENT_BODY TRUE
J 0
(2905 1555);
DISPLAY 0.872340 (2905 1555);
PAINT GREEN (2905 1555);
DISPLAY INVISIBLE (2905 1555);
FORCEPROP 1 LAST OFFPAGE TRUE
J 0
(3275 1525);
DISPLAY 0.872340 (3275 1525);
PAINT GREEN (3275 1525);
DISPLAY INVISIBLE (3275 1525);
FORCEPROP 2 LAST CDS_LIB mstr_standard
J 0
(2950 1650);
PAINT ORANGE (2950 1650);
DISPLAY INVISIBLE (2950 1650);
FORCEPROP 2 LAST PATH I244
J 0
(3125 1725);
DISPLAY 1.021277 (3125 1725);
PAINT ORANGE (3125 1725);
DISPLAY INVISIBLE (3125 1725);
FORCEADD VCC_CORE..1
(1150 2925);
FORCEPROP 3 LASTPIN (1150 2875) SIG_NAME P1V8_MCP_CPU0\g
J 0
(1160 2885);
DISPLAY 0.659574 (1160 2885);
PAINT MONO (1160 2885);
DISPLAY INVISIBLE (1160 2885);
FORCEPROP 1 LAST HDL_POWER P1V8_MCP_CPU0
J 1
(1150 2975);
DISPLAY 0.617021 (1150 2975);
PAINT GREEN (1150 2975);
FORCEPROP 1 LAST PATH I245
J 0
(1200 2950);
DISPLAY 0.872340 (1200 2950);
PAINT AQUA (1200 2950);
DISPLAY INVISIBLE (1200 2950);
FORCEPROP 2 LAST CDS_LIB mstr_symbols
J 0
(1150 2925);
PAINT ORANGE (1150 2925);
DISPLAY INVISIBLE (1150 2925);
FORCEADD CAP_A..1
R 2
(2125 3200);
FORCEPROP 1 LAST VALUE 0.1UF
J 2
(2075 3250);
DISPLAY 0.617021 (2075 3250);
PAINT SKYBLUE (2075 3250);
FORCEPROP 1 LAST LOCATION C4R2
J 2
(2075 3300);
DISPLAY 0.617021 (2075 3300);
PAINT AQUA (2075 3300);
FORCEPROP 1 LAST PACK_TYPE 0402V
J 2
(2075 3000);
DISPLAY 0.617021 (2075 3000);
PAINT SKYBLUE (2075 3000);
FORCEPROP 1 LAST VOLTAGE 16V
J 2
(2075 3200);
DISPLAY 0.617021 (2075 3200);
PAINT SKYBLUE (2075 3200);
FORCEPROP 0 LAST POP NOPOP
J 0
(1900 2950);
DISPLAY 0.638298 (1900 2950);
PAINT RED (1900 2950);
FORCEPROP 1 LAST MATERIAL X7R
J 2
(2075 3100);
DISPLAY 0.617021 (2075 3100);
PAINT SKYBLUE (2075 3100);
FORCEPROP 1 LAST TOLERANCE 10%
J 2
(2075 3150);
DISPLAY 0.617021 (2075 3150);
PAINT SKYBLUE (2075 3150);
FORCEPROP 1 LASTPIN (2125 3300) $PN 1
J 2
(2115 3280);
DISPLAY 0.617021 (2115 3280);
PAINT ORANGE (2115 3280);
FORCEPROP 1 LAST PART_NUMBER A36096-030
J 2
(2075 3050);
DISPLAY 0.617021 (2075 3050);
PAINT BLUE (2075 3050);
FORCEPROP 1 LASTPIN (2125 3100) $PN 2
J 2
(2115 3080);
DISPLAY 0.617021 (2115 3080);
PAINT ORANGE (2115 3080);
FORCEPROP 2 LAST CDS_LIB dev_discrete
J 0
(2125 3200);
PAINT ORANGE (2125 3200);
DISPLAY INVISIBLE (2125 3200);
FORCEPROP 1 LAST PATH I246
J 2
(2075 3350);
DISPLAY 0.978723 (2075 3350);
PAINT WHITE (2075 3350);
DISPLAY INVISIBLE (2075 3350);
FORCEPROP 2 LAST ROOM DEBUG
J 2
(2075 3400);
DISPLAY 1.021277 (2075 3400);
PAINT ORANGE (2075 3400);
DISPLAY INVISIBLE (2075 3400);
FORCEPROP 2 LAST CDS_SEC 1
J 0
(2075 3350);
PAINT ORANGE (2075 3350);
DISPLAY INVISIBLE (2075 3350);
FORCEPROP 2 LAST SEC_TYPE 0402V
J 2
(2075 3400);
DISPLAY 1.021277 (2075 3400);
PAINT ORANGE (2075 3400);
DISPLAY INVISIBLE (2075 3400);
FORCEPROP 2 LAST SEC 1
J 2
(2075 3400);
DISPLAY 0.680851 (2075 3400);
PAINT MONO (2075 3400);
DISPLAY INVISIBLE (2075 3400);
FORCEADD GND..1
(2125 3000);
FORCEPROP 3 LASTPIN (2125 3050) SIG_NAME GND\g
J 0
(2135 3060);
DISPLAY 0.659574 (2135 3060);
PAINT MONO (2135 3060);
DISPLAY INVISIBLE (2135 3060);
FORCEPROP 1 LAST HDL_POWER GND
J 0
(2125 3150);
PAINT GREEN (2125 3150);
DISPLAY INVISIBLE (2125 3150);
FORCEPROP 1 LAST BODY_TYPE PLUMBING
J 0
(2080 2957);
DISPLAY 0.340426 (2080 2957);
PAINT GREEN (2080 2957);
DISPLAY INVISIBLE (2080 2957);
FORCEPROP 2 LAST CDS_LIB mstr_symbols
J 0
(2125 3000);
PAINT ORANGE (2125 3000);
DISPLAY INVISIBLE (2125 3000);
FORCEPROP 1 LAST VOLTAGE 0.0V
J 0
(2080 2957);
DISPLAY 0.340426 (2080 2957);
PAINT SKYBLUE (2080 2957);
DISPLAY INVISIBLE (2080 2957);
FORCEPROP 1 LAST SIZE 1B
J 0
(2200 2950);
DISPLAY 2.382979 (2200 2950);
PAINT GREEN (2200 2950);
DISPLAY INVISIBLE (2200 2950);
FORCEPROP 1 LAST PATH I247
J 0
(2200 3000);
DISPLAY 0.872340 (2200 3000);
PAINT AQUA (2200 3000);
DISPLAY INVISIBLE (2200 3000);
FORCEADD CAP_A..1
R 2
(2125 2650);
FORCEPROP 1 LAST VOLTAGE 16V
J 2
(2075 2650);
DISPLAY 0.617021 (2075 2650);
PAINT SKYBLUE (2075 2650);
FORCEPROP 1 LAST TOLERANCE 10%
J 2
(2075 2600);
DISPLAY 0.617021 (2075 2600);
PAINT SKYBLUE (2075 2600);
FORCEPROP 1 LAST MATERIAL X7R
J 2
(2075 2550);
DISPLAY 0.617021 (2075 2550);
PAINT SKYBLUE (2075 2550);
FORCEPROP 1 LASTPIN (2125 2550) $PN 2
J 2
(2115 2530);
DISPLAY 0.617021 (2115 2530);
PAINT ORANGE (2115 2530);
FORCEPROP 1 LASTPIN (2125 2750) $PN 1
J 2
(2115 2730);
DISPLAY 0.617021 (2115 2730);
PAINT ORANGE (2115 2730);
FORCEPROP 1 LAST LOCATION C1M33
J 2
(2075 2750);
DISPLAY 0.617021 (2075 2750);
PAINT AQUA (2075 2750);
FORCEPROP 1 LAST VALUE 0.1UF
J 2
(2075 2700);
DISPLAY 0.617021 (2075 2700);
PAINT SKYBLUE (2075 2700);
FORCEPROP 0 LAST POP NOPOP
J 0
(1925 2400);
DISPLAY 0.638298 (1925 2400);
PAINT RED (1925 2400);
FORCEPROP 1 LAST PACK_TYPE 0402V
J 2
(2075 2450);
DISPLAY 0.617021 (2075 2450);
PAINT SKYBLUE (2075 2450);
FORCEPROP 1 LAST PART_NUMBER A36096-030
J 2
(2075 2500);
DISPLAY 0.617021 (2075 2500);
PAINT BLUE (2075 2500);
FORCEPROP 2 LAST CDS_LIB dev_discrete
J 0
(2125 2650);
PAINT ORANGE (2125 2650);
DISPLAY INVISIBLE (2125 2650);
FORCEPROP 2 LAST CDS_SEC 1
J 0
(2075 2800);
PAINT ORANGE (2075 2800);
DISPLAY INVISIBLE (2075 2800);
FORCEPROP 1 LAST PATH I248
J 2
(2075 2800);
DISPLAY 0.978723 (2075 2800);
PAINT WHITE (2075 2800);
DISPLAY INVISIBLE (2075 2800);
FORCEPROP 2 LAST ROOM DEBUG
J 2
(2075 2800);
DISPLAY 1.617021 (2075 2800);
PAINT WHITE (2075 2800);
DISPLAY INVISIBLE (2075 2800);
FORCEPROP 2 LAST BOM_COST DEBUG
J 0
(2075 2800);
DISPLAY 1.617021 (2075 2800);
PAINT WHITE (2075 2800);
DISPLAY INVISIBLE (2075 2800);
FORCEPROP 2 LAST SEC_TYPE 0402V
J 0
(2075 2850);
DISPLAY 1.021277 (2075 2850);
PAINT ORANGE (2075 2850);
DISPLAY INVISIBLE (2075 2850);
FORCEPROP 2 LAST SEC 1
J 0
(2075 2850);
DISPLAY 0.680851 (2075 2850);
PAINT MONO (2075 2850);
DISPLAY INVISIBLE (2075 2850);
FORCEADD GND..1
(2125 2450);
FORCEPROP 3 LASTPIN (2125 2500) SIG_NAME GND\g
J 0
(2135 2510);
DISPLAY 0.659574 (2135 2510);
PAINT MONO (2135 2510);
DISPLAY INVISIBLE (2135 2510);
FORCEPROP 1 LAST HDL_POWER GND
J 0
(2125 2600);
PAINT GREEN (2125 2600);
DISPLAY INVISIBLE (2125 2600);
FORCEPROP 1 LAST BODY_TYPE PLUMBING
J 0
(2080 2407);
DISPLAY 0.340426 (2080 2407);
PAINT GREEN (2080 2407);
DISPLAY INVISIBLE (2080 2407);
FORCEPROP 2 LAST ROOM DEBUG
J 0
(1650 2525);
DISPLAY 1.617021 (1650 2525);
PAINT WHITE (1650 2525);
DISPLAY INVISIBLE (1650 2525);
FORCEPROP 2 LAST BOM_COST DEBUG
J 0
(1650 2575);
DISPLAY 1.617021 (1650 2575);
PAINT WHITE (1650 2575);
DISPLAY INVISIBLE (1650 2575);
FORCEPROP 1 LAST VOLTAGE 0.0V
J 0
(2080 2407);
DISPLAY 0.340426 (2080 2407);
PAINT SKYBLUE (2080 2407);
DISPLAY INVISIBLE (2080 2407);
FORCEPROP 2 LAST CDS_LIB mstr_symbols
J 0
(2125 2450);
PAINT ORANGE (2125 2450);
DISPLAY INVISIBLE (2125 2450);
FORCEPROP 1 LAST SIZE 1B
J 0
(2200 2400);
DISPLAY 1.893617 (2200 2400);
PAINT GREEN (2200 2400);
DISPLAY INVISIBLE (2200 2400);
FORCEPROP 1 LAST PATH I249
J 0
(2200 2450);
DISPLAY 0.872340 (2200 2450);
PAINT AQUA (2200 2450);
DISPLAY INVISIBLE (2200 2450);
FORCEADD CAP_A..1
R 2
(2150 1825);
FORCEPROP 1 LAST PART_NUMBER A36096-030
J 2
(2100 1675);
DISPLAY 0.617021 (2100 1675);
PAINT BLUE (2100 1675);
FORCEPROP 1 LAST MATERIAL X7R
J 2
(2100 1725);
DISPLAY 0.617021 (2100 1725);
PAINT SKYBLUE (2100 1725);
FORCEPROP 1 LAST TOLERANCE 10%
J 2
(2100 1775);
DISPLAY 0.617021 (2100 1775);
PAINT SKYBLUE (2100 1775);
FORCEPROP 0 LAST POP NOPOP
J 0
(1950 1575);
DISPLAY 0.638298 (1950 1575);
PAINT RED (1950 1575);
FORCEPROP 1 LAST PACK_TYPE 0402V
J 2
(2100 1625);
DISPLAY 0.617021 (2100 1625);
PAINT SKYBLUE (2100 1625);
FORCEPROP 1 LAST VALUE 0.1UF
J 2
(2100 1875);
DISPLAY 0.617021 (2100 1875);
PAINT SKYBLUE (2100 1875);
FORCEPROP 1 LAST LOCATION C6M6
J 2
(2100 1925);
DISPLAY 0.617021 (2100 1925);
PAINT AQUA (2100 1925);
FORCEPROP 1 LASTPIN (2150 1725) $PN 2
J 2
(2140 1705);
DISPLAY 0.617021 (2140 1705);
PAINT ORANGE (2140 1705);
FORCEPROP 1 LASTPIN (2150 1925) $PN 1
J 2
(2140 1905);
DISPLAY 0.617021 (2140 1905);
PAINT ORANGE (2140 1905);
FORCEPROP 1 LAST VOLTAGE 16V
J 2
(2100 1825);
DISPLAY 0.617021 (2100 1825);
PAINT SKYBLUE (2100 1825);
FORCEPROP 2 LAST CDS_LIB dev_discrete
J 0
(2150 1825);
PAINT ORANGE (2150 1825);
DISPLAY INVISIBLE (2150 1825);
FORCEPROP 2 LAST SEC 1
J 0
(2100 2025);
DISPLAY 0.680851 (2100 2025);
PAINT MONO (2100 2025);
DISPLAY INVISIBLE (2100 2025);
FORCEPROP 2 LAST CDS_SEC 1
J 0
(2100 1975);
PAINT ORANGE (2100 1975);
DISPLAY INVISIBLE (2100 1975);
FORCEPROP 2 LAST BOM_COST DEBUG
J 0
(2100 1975);
DISPLAY 1.617021 (2100 1975);
PAINT WHITE (2100 1975);
DISPLAY INVISIBLE (2100 1975);
FORCEPROP 2 LAST ROOM DEBUG
J 2
(2100 1975);
DISPLAY 1.617021 (2100 1975);
PAINT WHITE (2100 1975);
DISPLAY INVISIBLE (2100 1975);
FORCEPROP 1 LAST PATH I250
J 2
(2100 1975);
DISPLAY 0.978723 (2100 1975);
PAINT WHITE (2100 1975);
DISPLAY INVISIBLE (2100 1975);
FORCEPROP 2 LAST SEC_TYPE 0402V
J 0
(2100 2025);
DISPLAY 1.021277 (2100 2025);
PAINT ORANGE (2100 2025);
DISPLAY INVISIBLE (2100 2025);
FORCEADD GND..1
(2150 1600);
FORCEPROP 3 LASTPIN (2150 1650) SIG_NAME GND\g
J 0
(2160 1660);
DISPLAY 0.659574 (2160 1660);
PAINT MONO (2160 1660);
DISPLAY INVISIBLE (2160 1660);
FORCEPROP 1 LAST HDL_POWER GND
J 0
(2150 1750);
PAINT GREEN (2150 1750);
DISPLAY INVISIBLE (2150 1750);
FORCEPROP 1 LAST BODY_TYPE PLUMBING
J 0
(2105 1557);
DISPLAY 0.340426 (2105 1557);
PAINT GREEN (2105 1557);
DISPLAY INVISIBLE (2105 1557);
FORCEPROP 2 LAST ROOM DEBUG
J 0
(1675 1675);
DISPLAY 1.617021 (1675 1675);
PAINT WHITE (1675 1675);
DISPLAY INVISIBLE (1675 1675);
FORCEPROP 2 LAST BOM_COST DEBUG
J 0
(1675 1725);
DISPLAY 1.617021 (1675 1725);
PAINT WHITE (1675 1725);
DISPLAY INVISIBLE (1675 1725);
FORCEPROP 1 LAST VOLTAGE 0.0V
J 0
(2105 1557);
DISPLAY 0.340426 (2105 1557);
PAINT SKYBLUE (2105 1557);
DISPLAY INVISIBLE (2105 1557);
FORCEPROP 2 LAST CDS_LIB mstr_symbols
J 0
(2150 1600);
PAINT ORANGE (2150 1600);
DISPLAY INVISIBLE (2150 1600);
FORCEPROP 1 LAST SIZE 1B
J 0
(2225 1550);
DISPLAY 1.893617 (2225 1550);
PAINT GREEN (2225 1550);
DISPLAY INVISIBLE (2225 1550);
FORCEPROP 1 LAST PATH I251
J 0
(2225 1600);
DISPLAY 0.872340 (2225 1600);
PAINT AQUA (2225 1600);
DISPLAY INVISIBLE (2225 1600);
FORCEADD NC7SB3157..1
R 2
(-2125 2325);
FORCEPROP 1 LAST PACK_TYPE SMLF
J 2
(-1950 2075);
DISPLAY 0.617021 (-1950 2075);
PAINT SKYBLUE (-1950 2075);
FORCEPROP 0 LAST GROUP MCP
J 0
(-2425 2050);
DISPLAY 0.638298 (-2425 2050);
PAINT BROWN (-2425 2050);
DISPLAY BOTH (-2425 2050);
FORCEPROP 1 LAST MATERIAL IC
J 2
(-1825 2075);
DISPLAY 0.617021 (-1825 2075);
PAINT SKYBLUE (-1825 2075);
FORCEPROP 2 LASTPIN (-1775 2175) $PN 5
J 0
(-1765 2185);
DISPLAY 0.617021 (-1765 2185);
PAINT ORANGE (-1765 2185);
FORCEPROP 1 LAST PART_NUMBER C99406-001
J 2
(-1825 2550);
DISPLAY 0.617021 (-1825 2550);
PAINT BLUE (-1825 2550);
FORCEPROP 2 LASTPIN (-1775 2375) $PN 3
J 0
(-1765 2385);
DISPLAY 0.617021 (-1765 2385);
PAINT ORANGE (-1765 2385);
FORCEPROP 2 LASTPIN (-2475 2175) $PN 2
J 2
(-2485 2185);
DISPLAY 0.617021 (-2485 2185);
PAINT ORANGE (-2485 2185);
FORCEPROP 2 LASTPIN (-2475 2325) $PN 4
J 2
(-2485 2335);
DISPLAY 0.617021 (-2485 2335);
PAINT ORANGE (-2485 2335);
FORCEPROP 2 LASTPIN (-1775 2475) $PN 6
J 0
(-1765 2485);
DISPLAY 0.617021 (-1765 2485);
PAINT ORANGE (-1765 2485);
FORCEPROP 2 LASTPIN (-1775 2275) $PN 1
J 0
(-1765 2285);
DISPLAY 0.617021 (-1765 2285);
PAINT ORANGE (-1765 2285);
FORCEPROP 1 LAST LOCATION U2M1
J 2
(-1825 2600);
DISPLAY 0.617021 (-1825 2600);
PAINT AQUA (-1825 2600);
FORCEPROP 1 LAST PATH I255
J 2
(-2200 2075);
DISPLAY 0.851064 (-2200 2075);
PAINT WHITE (-2200 2075);
DISPLAY INVISIBLE (-2200 2075);
FORCEPROP 2 LAST CDS_LIB mstr_analog
J 0
(-2125 2325);
PAINT MONO (-2125 2325);
DISPLAY INVISIBLE (-2125 2325);
FORCEPROP 2 LAST BOM_COST DEBUG
J 0
(-1825 2700);
DISPLAY 1.617021 (-1825 2700);
PAINT WHITE (-1825 2700);
DISPLAY INVISIBLE (-1825 2700);
FORCEPROP 2 LAST SEC_TYPE SMLF
J 0
(-1825 2650);
DISPLAY 1.021277 (-1825 2650);
PAINT ORANGE (-1825 2650);
DISPLAY INVISIBLE (-1825 2650);
FORCEPROP 2 LAST SEC 1
J 0
(-1825 2650);
DISPLAY 0.680851 (-1825 2650);
PAINT MONO (-1825 2650);
DISPLAY INVISIBLE (-1825 2650);
FORCEPROP 2 LAST ROOM DEBUG
J 0
(-1825 2650);
DISPLAY 1.617021 (-1825 2650);
PAINT WHITE (-1825 2650);
DISPLAY INVISIBLE (-1825 2650);
FORCEADD OFFPAGE..4
(-1100 2475);
FORCEPROP 2 LAST $XR0 191 
J 0
(-914 2475);
DISPLAY 0.638298 (-914 2475);
PAINT MONO (-914 2475);
FORCEPROP 1 LAST COMMENT_BODY TRUE
J 0
(-1125 2375);
DISPLAY 0.872340 (-1125 2375);
PAINT GREEN (-1125 2375);
DISPLAY INVISIBLE (-1125 2375);
FORCEPROP 1 LAST OFFPAGE TRUE
J 0
(-775 2350);
DISPLAY 0.872340 (-775 2350);
PAINT GREEN (-775 2350);
DISPLAY INVISIBLE (-775 2350);
FORCEPROP 2 LAST CDS_LIB mstr_standard
J 0
(-1100 2475);
PAINT MONO (-1100 2475);
DISPLAY INVISIBLE (-1100 2475);
FORCEPROP 2 LAST PATH I256
J 0
(-325 2525);
DISPLAY 1.021277 (-325 2525);
PAINT ORANGE (-325 2525);
DISPLAY INVISIBLE (-325 2525);
FORCEADD OFFPAGE..4
(-1100 2375);
FORCEPROP 2 LAST $XR0 113 
J 0
(-914 2375);
DISPLAY 0.638298 (-914 2375);
PAINT MONO (-914 2375);
FORCEPROP 2 LAST $XR1 63 
J 0
(-794 2375);
DISPLAY 0.638298 (-794 2375);
PAINT MONO (-794 2375);
FORCEPROP 1 LAST COMMENT_BODY TRUE
J 0
(-1125 2275);
DISPLAY 0.872340 (-1125 2275);
PAINT GREEN (-1125 2275);
DISPLAY INVISIBLE (-1125 2275);
FORCEPROP 1 LAST OFFPAGE TRUE
J 0
(-775 2250);
DISPLAY 0.872340 (-775 2250);
PAINT GREEN (-775 2250);
DISPLAY INVISIBLE (-775 2250);
FORCEPROP 2 LAST CDS_LIB mstr_standard
J 0
(-1100 2375);
PAINT MONO (-1100 2375);
DISPLAY INVISIBLE (-1100 2375);
FORCEPROP 2 LAST PATH I257
J 0
(-900 2425);
DISPLAY 1.021277 (-900 2425);
PAINT ORANGE (-900 2425);
DISPLAY INVISIBLE (-900 2425);
FORCEADD OFFPAGE..4
(-1100 2275);
FORCEPROP 2 LAST $XR1 29 
J 0
(-794 2275);
DISPLAY 0.638298 (-794 2275);
PAINT MONO (-794 2275);
FORCEPROP 2 LAST $XR0 113 
J 0
(-914 2275);
DISPLAY 0.638298 (-914 2275);
PAINT MONO (-914 2275);
FORCEPROP 1 LAST COMMENT_BODY TRUE
J 0
(-1125 2175);
DISPLAY 0.872340 (-1125 2175);
PAINT GREEN (-1125 2175);
DISPLAY INVISIBLE (-1125 2175);
FORCEPROP 1 LAST OFFPAGE TRUE
J 0
(-775 2150);
DISPLAY 0.872340 (-775 2150);
PAINT GREEN (-775 2150);
DISPLAY INVISIBLE (-775 2150);
FORCEPROP 2 LAST CDS_LIB mstr_standard
J 0
(-1100 2275);
PAINT MONO (-1100 2275);
DISPLAY INVISIBLE (-1100 2275);
FORCEPROP 2 LAST PATH I258
J 0
(-800 2325);
DISPLAY 1.021277 (-800 2325);
PAINT ORANGE (-800 2325);
DISPLAY INVISIBLE (-800 2325);
FORCEADD P3V3_STBY..1
(-1275 2100);
FORCEPROP 3 LASTPIN (-1275 2050) SIG_NAME P3V3_STBY\g
J 0
(-1265 2060);
DISPLAY 0.659574 (-1265 2060);
PAINT MONO (-1265 2060);
DISPLAY INVISIBLE (-1265 2060);
FORCEPROP 1 LAST HDL_POWER P3V3_STBY
J 0
(-1575 1975);
DISPLAY 0.872340 (-1575 1975);
PAINT ORANGE (-1575 1975);
DISPLAY INVISIBLE (-1575 1975);
FORCEPROP 1 LAST BODY_TYPE PLUMBING
J 0
(-1320 2057);
DISPLAY 0.340426 (-1320 2057);
PAINT GREEN (-1320 2057);
DISPLAY INVISIBLE (-1320 2057);
FORCEPROP 1 LAST VOLTAGE 3.3V
J 0
(-1320 2057);
DISPLAY 0.340426 (-1320 2057);
PAINT SKYBLUE (-1320 2057);
DISPLAY INVISIBLE (-1320 2057);
FORCEPROP 1 LAST SIZE 1B
J 0
(-1230 2122);
DISPLAY 0.340426 (-1230 2122);
PAINT GREEN (-1230 2122);
DISPLAY INVISIBLE (-1230 2122);
FORCEPROP 2 LAST CDS_LIB mstr_symbols
J 0
(-1275 2100);
PAINT ORANGE (-1275 2100);
DISPLAY INVISIBLE (-1275 2100);
FORCEPROP 1 LAST PATH I259
J 0
(-1230 2102);
DISPLAY 0.340426 (-1230 2102);
PAINT GREEN (-1230 2102);
DISPLAY INVISIBLE (-1230 2102);
FORCEADD GND..1
(-1275 1500);
FORCEPROP 3 LASTPIN (-1275 1550) SIG_NAME GND\g
J 0
(-1265 1560);
DISPLAY 0.659574 (-1265 1560);
PAINT MONO (-1265 1560);
DISPLAY INVISIBLE (-1265 1560);
FORCEPROP 1 LAST HDL_POWER GND
J 0
(-1275 1650);
PAINT GREEN (-1275 1650);
DISPLAY INVISIBLE (-1275 1650);
FORCEPROP 1 LAST BODY_TYPE PLUMBING
J 0
(-1320 1457);
DISPLAY 0.340426 (-1320 1457);
PAINT GREEN (-1320 1457);
DISPLAY INVISIBLE (-1320 1457);
FORCEPROP 2 LAST ROOM DEBUG
J 0
(-1750 1575);
DISPLAY 1.617021 (-1750 1575);
PAINT WHITE (-1750 1575);
DISPLAY INVISIBLE (-1750 1575);
FORCEPROP 2 LAST BOM_COST DEBUG
J 0
(-1750 1625);
DISPLAY 1.617021 (-1750 1625);
PAINT WHITE (-1750 1625);
DISPLAY INVISIBLE (-1750 1625);
FORCEPROP 1 LAST SIZE 1B
J 0
(-1200 1450);
DISPLAY 1.893617 (-1200 1450);
PAINT GREEN (-1200 1450);
DISPLAY INVISIBLE (-1200 1450);
FORCEPROP 1 LAST VOLTAGE 0.0V
J 0
(-1320 1457);
DISPLAY 0.340426 (-1320 1457);
PAINT SKYBLUE (-1320 1457);
DISPLAY INVISIBLE (-1320 1457);
FORCEPROP 1 LAST PATH I261
J 0
(-1200 1500);
DISPLAY 0.872340 (-1200 1500);
PAINT AQUA (-1200 1500);
DISPLAY INVISIBLE (-1200 1500);
FORCEPROP 2 LAST CDS_LIB mstr_symbols
J 0
(-1275 1500);
PAINT MONO (-1275 1500);
DISPLAY INVISIBLE (-1275 1500);
FORCEADD GND..1
(-2550 2025);
FORCEPROP 3 LASTPIN (-2550 2075) SIG_NAME GND\g
J 0
(-2540 2085);
DISPLAY 0.659574 (-2540 2085);
PAINT MONO (-2540 2085);
DISPLAY INVISIBLE (-2540 2085);
FORCEPROP 1 LAST HDL_POWER GND
J 0
(-2550 2175);
DISPLAY 0.872340 (-2550 2175);
PAINT GREEN (-2550 2175);
DISPLAY INVISIBLE (-2550 2175);
FORCEPROP 1 LAST BODY_TYPE PLUMBING
J 0
(-2595 1982);
DISPLAY 0.340426 (-2595 1982);
PAINT GREEN (-2595 1982);
DISPLAY INVISIBLE (-2595 1982);
FORCEPROP 1 LAST VOLTAGE 0.0V
J 0
(-2595 1982);
DISPLAY 0.340426 (-2595 1982);
PAINT SKYBLUE (-2595 1982);
DISPLAY INVISIBLE (-2595 1982);
FORCEPROP 1 LAST SIZE 1B
J 0
(-2475 1975);
DISPLAY 0.872340 (-2475 1975);
PAINT AQUA (-2475 1975);
DISPLAY INVISIBLE (-2475 1975);
FORCEPROP 1 LAST PATH I263
J 0
(-2475 2025);
DISPLAY 0.872340 (-2475 2025);
PAINT AQUA (-2475 2025);
DISPLAY INVISIBLE (-2475 2025);
FORCEPROP 2 LAST CDS_LIB mstr_symbols
J 0
(-2550 2025);
PAINT MONO (-2550 2025);
DISPLAY INVISIBLE (-2550 2025);
FORCEADD OFFPAGE..5
(-3050 2325);
FORCEPROP 2 LAST $XR0 113 
J 0
(-3305 2325);
DISPLAY 0.638298 (-3305 2325);
PAINT MONO (-3305 2325);
FORCEPROP 1 LAST COMMENT_BODY TRUE
J 0
(-2950 2250);
DISPLAY 0.872340 (-2950 2250);
PAINT GREEN (-2950 2250);
DISPLAY INVISIBLE (-2950 2250);
FORCEPROP 1 LAST OFFPAGE TRUE
J 0
(-2725 2200);
DISPLAY 0.872340 (-2725 2200);
PAINT GREEN (-2725 2200);
DISPLAY INVISIBLE (-2725 2200);
FORCEPROP 2 LAST PATH I264
J 0
(-3325 2375);
DISPLAY 1.021277 (-3325 2375);
PAINT ORANGE (-3325 2375);
DISPLAY INVISIBLE (-3325 2375);
FORCEPROP 2 LAST CDS_LIB mstr_standard
J 0
(-3050 2325);
PAINT MONO (-3050 2325);
DISPLAY INVISIBLE (-3050 2325);
FORCEADD CAP_A..1
R 2
(-1275 1825);
FORCEPROP 0 LAST GROUP MCP
J 0
(-1500 1575);
DISPLAY 0.638298 (-1500 1575);
PAINT BROWN (-1500 1575);
DISPLAY BOTH (-1500 1575);
FORCEPROP 1 LAST PACK_TYPE 0402V
J 2
(-1325 1625);
DISPLAY 0.617021 (-1325 1625);
PAINT SKYBLUE (-1325 1625);
FORCEPROP 1 LAST PART_NUMBER A36096-045
J 2
(-1325 1675);
DISPLAY 0.617021 (-1325 1675);
PAINT BLUE (-1325 1675);
FORCEPROP 1 LASTPIN (-1275 1725) $PN 2
J 2
(-1285 1705);
DISPLAY 0.617021 (-1285 1705);
PAINT ORANGE (-1285 1705);
FORCEPROP 1 LAST MATERIAL X7R
J 2
(-1325 1725);
DISPLAY 0.617021 (-1325 1725);
PAINT SKYBLUE (-1325 1725);
FORCEPROP 1 LAST VOLTAGE 25V
J 2
(-1325 1825);
DISPLAY 0.617021 (-1325 1825);
PAINT SKYBLUE (-1325 1825);
FORCEPROP 1 LAST TOLERANCE 10%
J 2
(-1325 1775);
DISPLAY 0.617021 (-1325 1775);
PAINT SKYBLUE (-1325 1775);
FORCEPROP 1 LAST LOCATION C1M34
J 2
(-1325 1925);
DISPLAY 0.617021 (-1325 1925);
PAINT AQUA (-1325 1925);
FORCEPROP 1 LAST VALUE 0.01UF
J 2
(-1325 1875);
DISPLAY 0.617021 (-1325 1875);
PAINT SKYBLUE (-1325 1875);
FORCEPROP 1 LASTPIN (-1275 1925) $PN 1
J 2
(-1285 1905);
DISPLAY 0.617021 (-1285 1905);
PAINT ORANGE (-1285 1905);
FORCEPROP 2 LAST BOM_COST DEBUG
J 0
(-1325 1975);
DISPLAY 1.617021 (-1325 1975);
PAINT WHITE (-1325 1975);
DISPLAY INVISIBLE (-1325 1975);
FORCEPROP 2 LAST CDS_SEC 1
J 0
(-1325 1975);
PAINT ORANGE (-1325 1975);
DISPLAY INVISIBLE (-1325 1975);
FORCEPROP 1 LAST PATH I265
J 2
(-1325 1975);
DISPLAY 0.978723 (-1325 1975);
PAINT WHITE (-1325 1975);
DISPLAY INVISIBLE (-1325 1975);
FORCEPROP 2 LAST ROOM DEBUG
J 2
(-1325 1975);
DISPLAY 1.617021 (-1325 1975);
PAINT WHITE (-1325 1975);
DISPLAY INVISIBLE (-1325 1975);
FORCEPROP 2 LAST CDS_LIB dev_discrete
J 0
(-1275 1825);
PAINT ORANGE (-1275 1825);
DISPLAY INVISIBLE (-1275 1825);
FORCEPROP 2 LAST SEC 1
J 0
(-1325 2025);
DISPLAY 0.680851 (-1325 2025);
PAINT MONO (-1325 2025);
DISPLAY INVISIBLE (-1325 2025);
FORCEPROP 2 LAST SEC_TYPE 0402V
J 0
(-1325 2025);
DISPLAY 1.021277 (-1325 2025);
PAINT ORANGE (-1325 2025);
DISPLAY INVISIBLE (-1325 2025);
FORCEADD CAP_A..1
R 2
(-1600 1825);
FORCEPROP 0 LAST GROUP MCP
J 0
(-1825 1575);
DISPLAY 0.638298 (-1825 1575);
PAINT BROWN (-1825 1575);
DISPLAY BOTH (-1825 1575);
FORCEPROP 1 LAST VOLTAGE 25V
J 2
(-1650 1825);
DISPLAY 0.617021 (-1650 1825);
PAINT SKYBLUE (-1650 1825);
FORCEPROP 1 LASTPIN (-1600 1925) $PN 1
J 2
(-1610 1905);
DISPLAY 0.617021 (-1610 1905);
PAINT ORANGE (-1610 1905);
FORCEPROP 1 LAST LOCATION C1M35
J 2
(-1650 1925);
DISPLAY 0.617021 (-1650 1925);
PAINT AQUA (-1650 1925);
FORCEPROP 1 LAST VALUE 0.01UF
J 2
(-1650 1875);
DISPLAY 0.617021 (-1650 1875);
PAINT SKYBLUE (-1650 1875);
FORCEPROP 1 LASTPIN (-1600 1725) $PN 2
J 2
(-1610 1705);
DISPLAY 0.617021 (-1610 1705);
PAINT ORANGE (-1610 1705);
FORCEPROP 1 LAST TOLERANCE 10%
J 2
(-1650 1775);
DISPLAY 0.617021 (-1650 1775);
PAINT SKYBLUE (-1650 1775);
FORCEPROP 1 LAST PACK_TYPE 0402V
J 2
(-1650 1625);
DISPLAY 0.617021 (-1650 1625);
PAINT SKYBLUE (-1650 1625);
FORCEPROP 1 LAST PART_NUMBER A36096-045
J 2
(-1650 1675);
DISPLAY 0.617021 (-1650 1675);
PAINT BLUE (-1650 1675);
FORCEPROP 1 LAST MATERIAL X7R
J 2
(-1650 1725);
DISPLAY 0.617021 (-1650 1725);
PAINT SKYBLUE (-1650 1725);
FORCEPROP 2 LAST CDS_LIB dev_discrete
J 0
(-1600 1825);
PAINT ORANGE (-1600 1825);
DISPLAY INVISIBLE (-1600 1825);
FORCEPROP 2 LAST BOM_COST DEBUG
J 0
(-1650 1975);
DISPLAY 1.617021 (-1650 1975);
PAINT WHITE (-1650 1975);
DISPLAY INVISIBLE (-1650 1975);
FORCEPROP 2 LAST CDS_SEC 1
J 0
(-1650 1975);
PAINT ORANGE (-1650 1975);
DISPLAY INVISIBLE (-1650 1975);
FORCEPROP 1 LAST PATH I266
J 2
(-1650 1975);
DISPLAY 0.978723 (-1650 1975);
PAINT WHITE (-1650 1975);
DISPLAY INVISIBLE (-1650 1975);
FORCEPROP 2 LAST ROOM DEBUG
J 2
(-1650 1975);
DISPLAY 1.617021 (-1650 1975);
PAINT WHITE (-1650 1975);
DISPLAY INVISIBLE (-1650 1975);
FORCEPROP 2 LAST SEC 1
J 0
(-1650 2025);
DISPLAY 0.680851 (-1650 2025);
PAINT MONO (-1650 2025);
DISPLAY INVISIBLE (-1650 2025);
FORCEPROP 2 LAST SEC_TYPE 0402V
J 0
(-1650 2025);
DISPLAY 1.021277 (-1650 2025);
PAINT ORANGE (-1650 2025);
DISPLAY INVISIBLE (-1650 2025);
FORCEADD CAP_A..1
R 2
(3025 3650);
FORCEPROP 0 LAST GROUP MCP
J 0
(2775 3425);
DISPLAY 0.638298 (2775 3425);
PAINT BROWN (2775 3425);
DISPLAY BOTH (2775 3425);
FORCEPROP 1 LASTPIN (3025 3750) $PN 1
J 2
(3015 3730);
DISPLAY 0.617021 (3015 3730);
PAINT ORANGE (3015 3730);
FORCEPROP 1 LASTPIN (3025 3550) $PN 2
J 2
(3015 3530);
DISPLAY 0.617021 (3015 3530);
PAINT ORANGE (3015 3530);
FORCEPROP 1 LAST VOLTAGE 25V
J 2
(2975 3650);
DISPLAY 0.617021 (2975 3650);
PAINT SKYBLUE (2975 3650);
FORCEPROP 1 LAST TOLERANCE 10%
J 2
(2975 3600);
DISPLAY 0.617021 (2975 3600);
PAINT SKYBLUE (2975 3600);
FORCEPROP 1 LAST LOCATION C1L20
J 2
(2975 3750);
DISPLAY 0.617021 (2975 3750);
PAINT AQUA (2975 3750);
FORCEPROP 1 LAST VALUE 0.01UF
J 2
(2975 3700);
DISPLAY 0.617021 (2975 3700);
PAINT SKYBLUE (2975 3700);
FORCEPROP 1 LAST PACK_TYPE 0402V
J 2
(2975 3450);
DISPLAY 0.617021 (2975 3450);
PAINT SKYBLUE (2975 3450);
FORCEPROP 1 LAST MATERIAL X7R
J 2
(2975 3550);
DISPLAY 0.617021 (2975 3550);
PAINT SKYBLUE (2975 3550);
FORCEPROP 1 LAST PART_NUMBER A36096-045
J 2
(2975 3500);
DISPLAY 0.617021 (2975 3500);
PAINT BLUE (2975 3500);
FORCEPROP 2 LAST SEC_TYPE 0402V
J 0
(2975 3850);
DISPLAY 1.021277 (2975 3850);
PAINT ORANGE (2975 3850);
DISPLAY INVISIBLE (2975 3850);
FORCEPROP 2 LAST SEC 1
J 0
(2975 3850);
DISPLAY 0.680851 (2975 3850);
PAINT MONO (2975 3850);
DISPLAY INVISIBLE (2975 3850);
FORCEPROP 2 LAST BOM_COST DEBUG
J 0
(2975 3800);
DISPLAY 1.617021 (2975 3800);
PAINT WHITE (2975 3800);
DISPLAY INVISIBLE (2975 3800);
FORCEPROP 2 LAST CDS_SEC 1
J 0
(2975 3800);
PAINT ORANGE (2975 3800);
DISPLAY INVISIBLE (2975 3800);
FORCEPROP 1 LAST PATH I267
J 2
(2975 3800);
DISPLAY 0.978723 (2975 3800);
PAINT WHITE (2975 3800);
DISPLAY INVISIBLE (2975 3800);
FORCEPROP 2 LAST ROOM DEBUG
J 2
(2975 3800);
DISPLAY 1.617021 (2975 3800);
PAINT WHITE (2975 3800);
DISPLAY INVISIBLE (2975 3800);
FORCEPROP 2 LAST CDS_LIB dev_discrete
J 0
(3025 3650);
PAINT ORANGE (3025 3650);
DISPLAY INVISIBLE (3025 3650);
FORCEADD GND..1
(3025 3450);
FORCEPROP 3 LASTPIN (3025 3500) SIG_NAME GND\g
J 0
(3035 3510);
DISPLAY 0.659574 (3035 3510);
PAINT MONO (3035 3510);
DISPLAY INVISIBLE (3035 3510);
FORCEPROP 1 LAST HDL_POWER GND
J 0
(3025 3600);
PAINT GREEN (3025 3600);
DISPLAY INVISIBLE (3025 3600);
FORCEPROP 1 LAST BODY_TYPE PLUMBING
J 0
(2980 3407);
DISPLAY 0.340426 (2980 3407);
PAINT GREEN (2980 3407);
DISPLAY INVISIBLE (2980 3407);
FORCEPROP 1 LAST PATH I268
J 0
(3100 3450);
DISPLAY 0.872340 (3100 3450);
PAINT AQUA (3100 3450);
DISPLAY INVISIBLE (3100 3450);
FORCEPROP 1 LAST SIZE 1B
J 0
(3100 3400);
DISPLAY 1.893617 (3100 3400);
PAINT GREEN (3100 3400);
DISPLAY INVISIBLE (3100 3400);
FORCEPROP 2 LAST CDS_LIB mstr_symbols
J 0
(3025 3450);
PAINT ORANGE (3025 3450);
DISPLAY INVISIBLE (3025 3450);
FORCEPROP 1 LAST VOLTAGE 0.0V
J 0
(2980 3407);
DISPLAY 0.340426 (2980 3407);
PAINT SKYBLUE (2980 3407);
DISPLAY INVISIBLE (2980 3407);
FORCEPROP 2 LAST BOM_COST DEBUG
J 0
(2550 3575);
DISPLAY 1.617021 (2550 3575);
PAINT WHITE (2550 3575);
DISPLAY INVISIBLE (2550 3575);
FORCEPROP 2 LAST ROOM DEBUG
J 0
(2550 3525);
DISPLAY 1.617021 (2550 3525);
PAINT WHITE (2550 3525);
DISPLAY INVISIBLE (2550 3525);
FORCEADD P3V3_STBY..1
(3025 3850);
FORCEPROP 3 LASTPIN (3025 3800) SIG_NAME P3V3_STBY\g
J 0
(3035 3810);
DISPLAY 0.659574 (3035 3810);
PAINT MONO (3035 3810);
DISPLAY INVISIBLE (3035 3810);
FORCEPROP 1 LAST HDL_POWER P3V3_STBY
J 0
(2725 3725);
DISPLAY 0.872340 (2725 3725);
PAINT ORANGE (2725 3725);
DISPLAY INVISIBLE (2725 3725);
FORCEPROP 1 LAST BODY_TYPE PLUMBING
J 0
(2980 3807);
DISPLAY 0.340426 (2980 3807);
PAINT GREEN (2980 3807);
DISPLAY INVISIBLE (2980 3807);
FORCEPROP 1 LAST SIZE 1B
J 0
(3070 3872);
DISPLAY 0.340426 (3070 3872);
PAINT GREEN (3070 3872);
DISPLAY INVISIBLE (3070 3872);
FORCEPROP 2 LAST CDS_LIB mstr_symbols
J 0
(3025 3850);
PAINT ORANGE (3025 3850);
DISPLAY INVISIBLE (3025 3850);
FORCEPROP 1 LAST PATH I269
J 0
(3070 3852);
DISPLAY 0.340426 (3070 3852);
PAINT GREEN (3070 3852);
DISPLAY INVISIBLE (3070 3852);
FORCEPROP 1 LAST VOLTAGE 3.3V
J 0
(2980 3807);
DISPLAY 0.340426 (2980 3807);
PAINT SKYBLUE (2980 3807);
DISPLAY INVISIBLE (2980 3807);
FORCEADD RES..2
(2450 3200);
FORCEPROP 0 LAST GROUP MCP
J 0
(2225 2975);
DISPLAY 0.638298 (2225 2975);
PAINT BROWN (2225 2975);
DISPLAY BOTH (2225 2975);
FORCEPROP 1 LAST LOCATION R4R6
J 0
(2295 3325);
DISPLAY 0.617021 (2295 3325);
PAINT AQUA (2295 3325);
FORCEPROP 1 LASTPIN (2450 3100) $PN 2
J 0
(2405 3110);
DISPLAY 0.787234 (2405 3110);
PAINT ORANGE (2405 3110);
FORCEPROP 1 LASTPIN (2450 3300) $PN 1
J 0
(2405 3262);
DISPLAY 0.787234 (2405 3262);
PAINT ORANGE (2405 3262);
FORCEPROP 1 LAST PACK_TYPE 0402
J 0
(2290 3025);
DISPLAY 0.617021 (2290 3025);
PAINT SKYBLUE (2290 3025);
FORCEPROP 1 LAST PART_NUMBER G21796-026
J 0
(2215 3075);
DISPLAY 0.617021 (2215 3075);
PAINT BLUE (2215 3075);
FORCEPROP 1 LAST TOLERANCE 1%
J 0
(2295 3225);
DISPLAY 0.617021 (2295 3225);
PAINT SKYBLUE (2295 3225);
FORCEPROP 1 LAST VALUE 1.00K
J 0
(2295 3275);
DISPLAY 0.617021 (2295 3275);
PAINT SKYBLUE (2295 3275);
FORCEPROP 1 LAST MATERIAL CHIP
J 0
(2290 3125);
DISPLAY 0.617021 (2290 3125);
PAINT SKYBLUE (2290 3125);
FORCEPROP 1 LAST WATTAGE 1/16W
J 0
(2290 3175);
DISPLAY 0.617021 (2290 3175);
PAINT SKYBLUE (2290 3175);
FORCEPROP 1 LAST PATH I270
J 0
(2500 3375);
DISPLAY 0.978723 (2500 3375);
PAINT WHITE (2500 3375);
DISPLAY INVISIBLE (2500 3375);
FORCEPROP 2 LAST SEC 1
J 0
(2500 3425);
DISPLAY 0.680851 (2500 3425);
PAINT MONO (2500 3425);
DISPLAY INVISIBLE (2500 3425);
FORCEPROP 2 LAST SEC_TYPE 0402
J 0
(2500 3425);
DISPLAY 1.021277 (2500 3425);
PAINT ORANGE (2500 3425);
DISPLAY INVISIBLE (2500 3425);
FORCEPROP 0 LAST ROOM PROC_SIDEBAND
J 0
(2500 3425);
DISPLAY 1.021277 (2500 3425);
PAINT ORANGE (2500 3425);
DISPLAY INVISIBLE (2500 3425);
FORCEPROP 2 LAST CDS_LIB mstr_discrete
J 0
(2450 3200);
PAINT MONO (2450 3200);
DISPLAY INVISIBLE (2450 3200);
FORCEADD RES..2
(2450 1825);
FORCEPROP 0 LAST GROUP MCP
J 0
(2225 1600);
DISPLAY 0.638298 (2225 1600);
PAINT BROWN (2225 1600);
DISPLAY BOTH (2225 1600);
FORCEPROP 1 LAST PACK_TYPE 0402
J 0
(2290 1650);
DISPLAY 0.617021 (2290 1650);
PAINT SKYBLUE (2290 1650);
FORCEPROP 1 LAST MATERIAL CHIP
J 0
(2290 1750);
DISPLAY 0.617021 (2290 1750);
PAINT SKYBLUE (2290 1750);
FORCEPROP 1 LASTPIN (2450 1925) $PN 1
J 0
(2405 1887);
DISPLAY 0.787234 (2405 1887);
PAINT ORANGE (2405 1887);
FORCEPROP 1 LASTPIN (2450 1725) $PN 2
J 0
(2405 1735);
DISPLAY 0.787234 (2405 1735);
PAINT ORANGE (2405 1735);
FORCEPROP 1 LAST PART_NUMBER G21796-026
J 0
(2215 1700);
DISPLAY 0.617021 (2215 1700);
PAINT BLUE (2215 1700);
FORCEPROP 1 LAST VALUE 1.00K
J 0
(2295 1900);
DISPLAY 0.617021 (2295 1900);
PAINT SKYBLUE (2295 1900);
FORCEPROP 1 LAST TOLERANCE 1%
J 0
(2295 1850);
DISPLAY 0.617021 (2295 1850);
PAINT SKYBLUE (2295 1850);
FORCEPROP 1 LAST WATTAGE 1/16W
J 0
(2290 1800);
DISPLAY 0.617021 (2290 1800);
PAINT SKYBLUE (2290 1800);
FORCEPROP 1 LAST LOCATION R6M8
J 0
(2295 1950);
DISPLAY 0.617021 (2295 1950);
PAINT AQUA (2295 1950);
FORCEPROP 2 LAST SEC 1
J 0
(2500 2050);
DISPLAY 0.680851 (2500 2050);
PAINT MONO (2500 2050);
DISPLAY INVISIBLE (2500 2050);
FORCEPROP 2 LAST SEC_TYPE 0402
J 0
(2500 2050);
DISPLAY 1.021277 (2500 2050);
PAINT ORANGE (2500 2050);
DISPLAY INVISIBLE (2500 2050);
FORCEPROP 0 LAST ROOM PROC_SIDEBAND
J 0
(2500 2050);
DISPLAY 1.021277 (2500 2050);
PAINT ORANGE (2500 2050);
DISPLAY INVISIBLE (2500 2050);
FORCEPROP 2 LAST CDS_LIB mstr_discrete
J 0
(2450 1825);
PAINT MONO (2450 1825);
DISPLAY INVISIBLE (2450 1825);
FORCEPROP 1 LAST PATH I271
J 0
(2500 2000);
DISPLAY 0.978723 (2500 2000);
PAINT WHITE (2500 2000);
DISPLAY INVISIBLE (2500 2000);
FORCEADD RES..1
(1600 3750);
FORCEPROP 1 LAST PART_NUMBER G21497-005
J 0
(1575 3650);
DISPLAY 0.617021 (1575 3650);
PAINT BLUE (1575 3650);
FORCEPROP 1 LAST VALUE 0.0
J 2
(1475 3700);
DISPLAY 0.617021 (1475 3700);
PAINT SKYBLUE (1475 3700);
FORCEPROP 1 LAST LOCATION R5W1
J 0
(1550 3800);
DISPLAY 0.617021 (1550 3800);
PAINT AQUA (1550 3800);
FORCEPROP 1 LASTPIN (1500 3750) $PN 1
J 0
(1512 3762);
DISPLAY 0.617021 (1512 3762);
PAINT ORANGE (1512 3762);
FORCEPROP 1 LASTPIN (1700 3750) $PN 2
J 0
(1662 3762);
DISPLAY 0.617021 (1662 3762);
PAINT ORANGE (1662 3762);
FORCEPROP 1 LAST WATTAGE 1/16W
J 2
(1675 3700);
DISPLAY 0.617021 (1675 3700);
PAINT SKYBLUE (1675 3700);
FORCEPROP 1 LAST MATERIAL CHIP
J 0
(1700 3700);
DISPLAY 0.617021 (1700 3700);
PAINT SKYBLUE (1700 3700);
FORCEPROP 1 LAST PACK_TYPE 0402
J 0
(1475 3650);
DISPLAY 0.617021 (1475 3650);
PAINT SKYBLUE (1475 3650);
FORCEPROP 1 LAST TOLERANCE 5%
J 0
(1500 3700);
DISPLAY 0.617021 (1500 3700);
PAINT SKYBLUE (1500 3700);
FORCEPROP 0 LAST GROUP MCP
J 0
(1600 3600);
DISPLAY 0.638298 (1600 3600);
PAINT BROWN (1600 3600);
DISPLAY BOTH (1600 3600);
FORCEPROP 2 LAST CDS_LIB mstr_discrete
J 0
(1600 3750);
PAINT ORANGE (1600 3750);
DISPLAY INVISIBLE (1600 3750);
FORCEPROP 2 LAST SEC 1
J 0
(1550 3950);
DISPLAY 0.680851 (1550 3950);
PAINT MONO (1550 3950);
DISPLAY INVISIBLE (1550 3950);
FORCEPROP 2 LAST SEC_TYPE 0402
J 0
(1550 3950);
DISPLAY 1.021277 (1550 3950);
PAINT ORANGE (1550 3950);
DISPLAY INVISIBLE (1550 3950);
FORCEPROP 1 LAST PATH I272
J 0
(1550 3900);
DISPLAY 0.978723 (1550 3900);
PAINT WHITE (1550 3900);
DISPLAY INVISIBLE (1550 3900);
FORCEADD RES..1
(1600 2375);
FORCEPROP 1 LAST LOCATION R5W2
J 0
(1550 2425);
DISPLAY 0.617021 (1550 2425);
PAINT AQUA (1550 2425);
FORCEPROP 1 LAST MATERIAL CHIP
J 0
(1700 2325);
DISPLAY 0.617021 (1700 2325);
PAINT SKYBLUE (1700 2325);
FORCEPROP 1 LAST PART_NUMBER G21497-005
J 0
(1575 2275);
DISPLAY 0.617021 (1575 2275);
PAINT BLUE (1575 2275);
FORCEPROP 1 LAST WATTAGE 1/16W
J 2
(1675 2325);
DISPLAY 0.617021 (1675 2325);
PAINT SKYBLUE (1675 2325);
FORCEPROP 1 LAST PACK_TYPE 0402
J 0
(1475 2275);
DISPLAY 0.617021 (1475 2275);
PAINT SKYBLUE (1475 2275);
FORCEPROP 1 LAST TOLERANCE 5%
J 0
(1500 2325);
DISPLAY 0.617021 (1500 2325);
PAINT SKYBLUE (1500 2325);
FORCEPROP 1 LAST VALUE 0.0
J 2
(1475 2325);
DISPLAY 0.617021 (1475 2325);
PAINT SKYBLUE (1475 2325);
FORCEPROP 0 LAST GROUP MCP
J 0
(1550 2225);
DISPLAY 0.638298 (1550 2225);
PAINT BROWN (1550 2225);
DISPLAY BOTH (1550 2225);
FORCEPROP 2 LAST CDS_LIB mstr_discrete
J 0
(1600 2375);
PAINT MONO (1600 2375);
DISPLAY INVISIBLE (1600 2375);
FORCEPROP 1 LAST PATH I273
J 0
(1550 2525);
DISPLAY 0.978723 (1550 2525);
PAINT WHITE (1550 2525);
DISPLAY INVISIBLE (1550 2525);
FORCEPROP 1 LASTPIN (1500 2375) $PN 1
J 0
(1512 2387);
DISPLAY 0.787234 (1512 2387);
PAINT ORANGE (1512 2387);
DISPLAY INVISIBLE (1512 2387);
FORCEPROP 1 LASTPIN (1700 2375) $PN 2
J 0
(1662 2387);
DISPLAY 0.787234 (1662 2387);
PAINT ORANGE (1662 2387);
DISPLAY INVISIBLE (1662 2387);
FORCEADD CAD_NOTE..1
(2000 1475);
FORCEPROP 0 LAST L2 INCHES OF CORRESPONDING RESISTOR
J 0
(1850 1275);
DISPLAY 0.808511 (1850 1275);
PAINT ORANGE (1850 1275);
FORCEPROP 0 LAST L1 PLACE DECOUPLING CAPS WITHIN 0.5
J 0
(1850 1350);
DISPLAY 0.808511 (1850 1350);
PAINT ORANGE (1850 1350);
FORCEPROP 1 LAST COMMENT_BODY TRUE
J 0
(2025 1575);
DISPLAY 0.978723 (2025 1575);
PAINT ORANGE (2025 1575);
DISPLAY INVISIBLE (2025 1575);
FORCEPROP 2 LAST CDS_LIB mstr_symbols
J 0
(2000 1475);
PAINT ORANGE (2000 1475);
DISPLAY INVISIBLE (2000 1475);
FORCEADD CAD_NOTE..1
(2800 2750);
FORCEPROP 0 LAST L1 PLACE U1M5 AND R1M22 NEAR CPU1 PKG PIN
J 0
(2650 2625);
DISPLAY 0.808511 (2650 2625);
PAINT ORANGE (2650 2625);
FORCEPROP 1 LAST COMMENT_BODY TRUE
J 0
(2825 2850);
DISPLAY 0.978723 (2825 2850);
PAINT ORANGE (2825 2850);
DISPLAY INVISIBLE (2825 2850);
FORCEPROP 2 LAST CDS_LIB mstr_symbols
J 0
(2800 2750);
PAINT ORANGE (2800 2750);
DISPLAY INVISIBLE (2800 2750);
FORCEADD DESIGN_NOTE..1
(25 675);
FORCEPROP 0 LAST L1 ADDITIONAL LOGIC WILL BE REQUIRED
J 0
(-175 550);
DISPLAY 1.021277 (-175 550);
PAINT ORANGE (-175 550);
FORCEPROP 0 LAST L2 ON THE ADAPTER BOARD FOR RC CPU SKU TO CD CPU SKU
J 0
(-175 475);
DISPLAY 1.021277 (-175 475);
PAINT ORANGE (-175 475);
FORCEPROP 1 LAST COMMENT_BODY TRUE
J 0
(50 775);
DISPLAY 0.978723 (50 775);
PAINT ORANGE (50 775);
DISPLAY INVISIBLE (50 775);
FORCEPROP 2 LAST CDS_LIB mstr_symbols
J 0
(25 675);
PAINT ORANGE (25 675);
DISPLAY INVISIBLE (25 675);
FORCEADD DESIGN_NOTE..1
(-2625 4925);
FORCEPROP 0 LAST L1 TCK AND TMS SERIES RES VALUE TBD
J 0
(-2825 4800);
DISPLAY 0.808511 (-2825 4800);
PAINT ORANGE (-2825 4800);
FORCEPROP 1 LAST COMMENT_BODY TRUE
J 0
(-2600 5025);
DISPLAY 0.978723 (-2600 5025);
PAINT ORANGE (-2600 5025);
DISPLAY INVISIBLE (-2600 5025);
FORCEPROP 2 LAST CDS_LIB mstr_symbols
J 0
(-2625 4925);
PAINT ORANGE (-2625 4925);
DISPLAY INVISIBLE (-2625 4925);
FORCEADD BOM_NOTE..1
(2050 1200);
FORCEPROP 0 LAST L1 R1M21 MUST BE DEPOPPED IN VOLUME
J 0
(1925 1075);
DISPLAY 0.808511 (1925 1075);
PAINT ORANGE (1925 1075);
FORCEPROP 1 LAST COMMENT_BODY TRUE
J 0
(2075 1300);
DISPLAY 0.978723 (2075 1300);
PAINT ORANGE (2075 1300);
DISPLAY INVISIBLE (2075 1300);
FORCEPROP 2 LAST CDS_LIB mstr_symbols
J 0
(2050 1200);
PAINT ORANGE (2050 1200);
DISPLAY INVISIBLE (2050 1200);
FORCEADD INTEL_CORP_BPAGE..1
(4200 75);
FORCEPROP 1 LAST CDS_CON_LAST_MODIFIED Fri Jun 16 17:48:45 2017
J 0
(2775 400);
PAINT ORANGE (2775 400);
DISPLAY INVISIBLE (2775 400);
FORCEPROP 1 LAST CUSTOM_TXT_CDS <CURRENT_DESIGN_SHEET> OF <TOTAL_DESIGN_SHEETS>
J 0
(3700 100);
PAINT ORANGE (3700 100);
FORCEPROP 1 LAST CUSTOM_TXT_CDS <CON_LAST_MODIFIED>
J 0
(200 175);
PAINT ORANGE (200 175);
FORCEPROP 2 LAST CUSTOM_TXT_CDS <XR_PAGE_TITLE>
J 0
(-3690 5325);
DISPLAY 0.638298 (-3690 5325);
PAINT PINK (-3690 5325);
DISPLAY INVISIBLE (-3690 5325);
FORCEPROP 1 LAST SCH_TITLE MCP JTAG
J 0
(-3750 125);
DISPLAY 1.212766 (-3750 125);
PAINT YELLOW (-3750 125);
FORCEPROP 2 LAST CDS_XR_PAGE_TITLE CR-113 : @BASEBOARD_FAB2_LIB.BASEBOARD_FAB2(SCH_1):PAGE113
J 0
(-3690 5325);
DISPLAY 0.638298 (-3690 5325);
PAINT PINK (-3690 5325);
DISPLAY INVISIBLE (-3690 5325);
FORCEPROP 1 LAST COMMENT_BODY TRUE
J 0
(4212 87);
DISPLAY 0.468085 (4212 87);
PAINT PEACH (4212 87);
DISPLAY INVISIBLE (4212 87);
FORCEPROP 2 LAST PAGE_BORDER TRUE
J 0
(-3690 5325);
DISPLAY 0.638298 (-3690 5325);
PAINT PINK (-3690 5325);
DISPLAY INVISIBLE (-3690 5325);
FORCEPROP 2 LAST CDS_LIB mstr_symbols
J 0
(4200 75);
PAINT ORANGE (4200 75);
DISPLAY INVISIBLE (4200 75);
FORCEADD CAD_NOTE..1
(2800 3275);
FORCEPROP 0 LAST L1 PLACE U4R1 AND R4R6 NEAR CPU0 PKG PIN
J 0
(2650 3150);
DISPLAY 0.808511 (2650 3150);
PAINT ORANGE (2650 3150);
FORCEPROP 1 LAST COMMENT_BODY TRUE
J 0
(2825 3375);
DISPLAY 0.978723 (2825 3375);
PAINT ORANGE (2825 3375);
DISPLAY INVISIBLE (2825 3375);
FORCEPROP 2 LAST CDS_LIB mstr_symbols
J 0
(2800 3275);
PAINT ORANGE (2800 3275);
DISPLAY INVISIBLE (2800 3275);
FORCEADD CAD_NOTE..1
(2975 4125);
FORCEPROP 0 LAST L1 PLACE U9A5 AND R9B9 NEAR CPU1 PKG PIN
J 0
(2825 4000);
DISPLAY 0.808511 (2825 4000);
PAINT ORANGE (2825 4000);
FORCEPROP 1 LAST COMMENT_BODY TRUE
J 0
(3000 4225);
DISPLAY 0.978723 (3000 4225);
PAINT ORANGE (3000 4225);
DISPLAY INVISIBLE (3000 4225);
FORCEPROP 2 LAST CDS_LIB mstr_symbols
J 0
(2975 4125);
PAINT ORANGE (2975 4125);
DISPLAY INVISIBLE (2975 4125);
FORCEADD DNS..2
(1405 4220);
PAINT RED (1405 4220);
FORCEPROP 1 LAST COMMENT_BODY TRUE
R 1
J 0
(1480 3995);
DISPLAY 0.872340 (1480 3995);
PAINT GREEN (1480 3995);
DISPLAY INVISIBLE (1480 3995);
FORCEPROP 2 LAST CDS_LIB mstr_misc
J 0
(1405 4220);
PAINT ORANGE (1405 4220);
DISPLAY INVISIBLE (1405 4220);
FORCEADD CAD_NOTE..1
(2800 1900);
FORCEPROP 0 LAST L1 PLACE U6M1 AND R6M8 NEAR CPU1 PKG PIN
J 0
(2650 1775);
DISPLAY 0.808511 (2650 1775);
PAINT ORANGE (2650 1775);
FORCEPROP 1 LAST COMMENT_BODY TRUE
J 0
(2825 2000);
DISPLAY 0.978723 (2825 2000);
PAINT ORANGE (2825 2000);
DISPLAY INVISIBLE (2825 2000);
FORCEPROP 2 LAST CDS_LIB mstr_symbols
J 0
(2800 1900);
PAINT ORANGE (2800 1900);
DISPLAY INVISIBLE (2800 1900);
FORCEADD CAD_NOTE..1
(3350 3725);
FORCEPROP 0 LAST L1 PLACE CAP NEAR 74CBTLV1G125
J 0
(3200 3600);
DISPLAY 0.808511 (3200 3600);
PAINT ORANGE (3200 3600);
FORCEPROP 1 LAST COMMENT_BODY TRUE
J 0
(3375 3825);
DISPLAY 0.978723 (3375 3825);
PAINT ORANGE (3375 3825);
DISPLAY INVISIBLE (3375 3825);
FORCEPROP 2 LAST CDS_LIB mstr_symbols
J 0
(3350 3725);
PAINT ORANGE (3350 3725);
DISPLAY INVISIBLE (3350 3725);
FORCEADD CAD_NOTE..1
(-1925 1325);
FORCEPROP 0 LAST L1 PLACE CAP NEAR 74CBTLV1G125
J 0
(-2075 1200);
DISPLAY 0.808511 (-2075 1200);
PAINT ORANGE (-2075 1200);
FORCEPROP 1 LAST COMMENT_BODY TRUE
J 0
(-1900 1425);
DISPLAY 0.978723 (-1900 1425);
PAINT ORANGE (-1900 1425);
DISPLAY INVISIBLE (-1900 1425);
FORCEPROP 2 LAST CDS_LIB mstr_symbols
J 0
(-1925 1325);
PAINT MONO (-1925 1325);
DISPLAY INVISIBLE (-1925 1325);
FORCEADD DESIGN_NOTE..1
(-3325 575);
FORCEPROP 0 LAST L1 MCP JTAG FOR DEBUG USE ONLY
J 0
(-3525 375);
DISPLAY 2.000000 (-3525 375);
PAINT ORANGE (-3525 375);
FORCEPROP 1 LAST COMMENT_BODY TRUE
J 0
(-3300 675);
DISPLAY 0.978723 (-3300 675);
PAINT ORANGE (-3300 675);
DISPLAY INVISIBLE (-3300 675);
FORCEPROP 2 LAST CDS_LIB mstr_symbols
J 0
(-3325 575);
PAINT ORANGE (-3325 575);
DISPLAY INVISIBLE (-3325 575);
FORCEADD BOM_NOTE..1
(425 4275);
FORCEPROP 0 LAST L1 R1M23 MUST BE UNPOPPED IN DEBUG
J 0
(275 4150);
DISPLAY 0.808511 (275 4150);
PAINT ORANGE (275 4150);
FORCEPROP 0 LAST L2 R1M23 MUST BE POPPED IN VOLUME
J 0
(275 4100);
DISPLAY 0.808511 (275 4100);
PAINT ORANGE (275 4100);
FORCEPROP 1 LAST COMMENT_BODY TRUE
J 0
(450 4375);
DISPLAY 0.978723 (450 4375);
PAINT ORANGE (450 4375);
DISPLAY INVISIBLE (450 4375);
FORCEPROP 2 LAST CDS_LIB mstr_symbols
J 0
(425 4275);
PAINT ORANGE (425 4275);
DISPLAY INVISIBLE (425 4275);
WIRE 16 -1 (-2500 3375)(-2500 3275);
WIRE 16 -1 (-2425 3375)(-2500 3375);
WIRE 16 -1 (-1150 4250)(-1150 4275);
WIRE 16 -1 (-1150 4275)(-1150 4475);
WIRE 16 -1 (-1225 4275)(-1150 4275);
WIRE 16 -1 (-1225 4475)(-1150 4475);
WIRE 16 -1 (-1250 2775)(-1250 2800);
WIRE 16 -1 (-1250 2800)(-1550 2800);
WIRE 16 -1 (-1250 2925)(-1250 2800);
WIRE 16 -1 (-1550 2800)(-1550 2925);
WIRE 16 -1 (-2250 1150)(-2250 1100);
WIRE 16 -1 (-975 4500)(-975 4550);
WIRE 16 -1 (-1250 3250)(-1250 3200);
WIRE 16 -1 (-1250 3200)(-1550 3200);
WIRE 16 -1 (-1250 3125)(-1250 3200);
WIRE 16 -1 (-1550 3375)(-1550 3200);
WIRE 16 -1 (-1550 3125)(-1550 3200);
WIRE 16 -1 (-1550 3375)(-1725 3375);
WIRE 16 -1 (-2250 1400)(-2250 1350);
WIRE 16 -1 (-1100 4800)(-1100 4850);
WIRE 16 -1 (-975 4800)(-1100 4800);
WIRE 16 -1 (-1100 4425)(-1100 4800);
WIRE 16 -1 (-1225 4425)(-1100 4425);
WIRE 16 -1 (-975 4750)(-975 4800);
WIRE 16 -1 (2600 4050)(2600 4000);
WIRE 16 -1 (3950 4350)(3950 4400);
WIRE 16 -1 (3950 4400)(3900 4400);
WIRE 16 -1 (1400 4125)(1400 4000);
WIRE 16 -1 (3575 1200)(3575 1225);
WIRE 16 -1 (3575 1200)(3425 1200);
WIRE 16 -1 (3675 1200)(3575 1200);
WIRE 16 -1 (3675 1200)(3675 1125);
WIRE 16 -1 (3425 1200)(3175 1200);
WIRE 16 -1 (3425 1125)(3425 1200);
WIRE 16 -1 (2925 1200)(3175 1200);
WIRE 16 -1 (3175 1125)(3175 1200);
WIRE 16 -1 (2925 1125)(2925 1200);
WIRE 16 -1 (900 2050)(900 2000);
WIRE 16 -1 (1150 2000)(900 2000);
WIRE 16 -1 (1150 2375)(1150 2000);
WIRE 16 -1 (1350 2000)(1150 2000);
WIRE 16 -1 (1500 2375)(1150 2375);
WIRE 16 -1 (900 3425)(900 3375);
WIRE 16 -1 (900 3375)(1150 3375);
WIRE 16 -1 (1150 3375)(1150 3750);
WIRE 16 -1 (1375 3375)(1150 3375);
WIRE 16 -1 (1500 3750)(1150 3750);
WIRE 16 -1 (1150 2825)(1150 2875);
WIRE 16 -1 (1350 2825)(1150 2825);
WIRE 16 -1 (2125 3050)(2125 3100);
WIRE 16 -1 (2125 2500)(2125 2550);
WIRE 16 -1 (2150 1725)(2150 1650);
WIRE 16 -1 (-1275 2050)(-1275 2000);
WIRE 16 -1 (-1275 2000)(-1600 2000);
WIRE 16 -1 (-1275 1925)(-1275 2000);
WIRE 16 -1 (-1600 2175)(-1600 2000);
WIRE 16 -1 (-1600 1925)(-1600 2000);
WIRE 16 -1 (-1600 2175)(-1775 2175);
WIRE 16 -1 (-1275 1550)(-1275 1575);
WIRE 16 -1 (-1275 1575)(-1600 1575);
WIRE 16 -1 (-1275 1725)(-1275 1575);
WIRE 16 -1 (-1600 1725)(-1600 1575);
WIRE 16 -1 (-2550 2175)(-2550 2075);
WIRE 16 -1 (-2475 2175)(-2550 2175);
WIRE 16 -1 (3025 3550)(3025 3500);
WIRE 16 -1 (3025 3800)(3025 3750);
WIRE 3 -1 (-2900 5000)(-2900 4750);
WIRE 3 -1 (-1850 5000)(-2900 5000);
WIRE 3 -1 (-2900 4750)(-1850 4750);
WIRE 3 -1 (-1850 4750)(-1850 5000);
WIRE 3 682 (1175 1750)(1175 525);
WIRE 3 682 (25 1750)(1175 1750);
WIRE 3 682 (25 1750)(25 4975);
WIRE 16 -1 (-1150 2475)(-1775 2475);
FORCEPROP 2 LAST SIG_NAME FM_CPU0_CD_PRES
J 0
(-1675 2485);
DISPLAY 0.617021 (-1675 2485);
PAINT ORANGE (-1675 2485);
WIRE 69 -1 (500 1350)(200 1350);
WIRE 69 -1 (500 1450)(500 1350);
WIRE 69 -1 (500 1550)(500 1450);
WIRE 69 -1 (500 1650)(500 1550);
WIRE 69 -1 (500 1650)(200 1650);
WIRE 69 -1 (200 1450)(200 1350);
WIRE 69 -1 (200 1450)(500 1450);
WIRE 69 -1 (-150 1350)(200 1350);
WIRE 69 -1 (-150 1350)(-650 1350);
WIRE 69 -1 (200 1550)(200 1450);
WIRE 69 -1 (200 1650)(200 1550);
WIRE 69 -1 (200 1550)(500 1550);
WIRE 69 -1 (-150 1650)(200 1650);
WIRE 69 -1 (-150 1450)(-150 1350);
WIRE 69 -1 (-150 1450)(200 1450);
WIRE 69 -1 (-650 1350)(-1100 1350);
WIRE 69 -1 (-1100 1350)(-1100 1450);
WIRE 69 -1 (-150 1550)(-150 1450);
WIRE 69 -1 (-150 1650)(-150 1550);
WIRE 69 -1 (-150 1550)(200 1550);
WIRE 69 -1 (-150 1650)(-650 1650);
WIRE 69 -1 (-650 1650)(-1100 1650);
WIRE 69 -1 (-650 1450)(-650 1350);
WIRE 69 -1 (-650 1450)(-150 1450);
WIRE 69 -1 (-1100 1450)(-650 1450);
WIRE 69 -1 (-650 1550)(-650 1450);
WIRE 69 -1 (-650 1650)(-650 1550);
WIRE 69 -1 (-650 1550)(-150 1550);
WIRE 69 -1 (-1100 1450)(-1100 1550);
WIRE 69 -1 (-1100 1550)(-1100 1650);
WIRE 69 -1 (-1100 1550)(-650 1550);
WIRE 3 682 (2100 3850)(2100 4650);
WIRE 3 682 (2100 4650)(4050 4650);
WIRE 3 682 (2100 3850)(1250 3850);
WIRE 3 682 (1250 3850)(1250 1550);
WIRE 3 682 (4050 4650)(4050 3375);
WIRE 3 682 (4050 3375)(2500 3375);
WIRE 3 682 (1250 1550)(2500 1550);
WIRE 3 682 (2500 1550)(2500 3375);
WIRE 16 -1 (-2100 4475)(-1525 4475);
FORCEPROP 0 LAST SIG_NAME JTAG_MCP_TCK_R
J 0
(-2050 4485);
DISPLAY 0.617021 (-2050 4485);
PAINT ORANGE (-2050 4485);
FORCEPROP 2 LASTPROP $XRERR UNIQUE?
J 0
(-2290 4485);
DISPLAY 0.638298 (-2290 4485);
PAINT MONO (-2290 4485);
DISPLAY INVISIBLE (-2290 4485);
WIRE 16 -1 (-2100 4625)(-2100 4475);
WIRE 16 -1 (-2500 4625)(-2100 4625);
WIRE 16 -1 (-3075 4625)(-2700 4625);
FORCEPROP 0 LAST SIG_NAME JTAG_MCP_TCK
J 0
(-3075 4635);
DISPLAY 0.617021 (-3075 4635);
PAINT ORANGE (-3075 4635);
WIRE 16 -1 (-1100 3675)(-1725 3675);
FORCEPROP 2 LAST SIG_NAME FM_CPU1_CD_PRES_N
J 0
(-1625 3685);
DISPLAY 0.617021 (-1625 3685);
PAINT ORANGE (-1625 3685);
WIRE 16 -1 (-1100 3575)(-1725 3575);
FORCEPROP 0 LAST SIG_NAME JTAG_MCP_CPU1_TDO
J 0
(-1625 3585);
DISPLAY 0.617021 (-1625 3585);
PAINT ORANGE (-1625 3585);
WIRE 3 682 (2925 4500)(2925 4375);
WIRE 3 682 (3350 4500)(2925 4500);
WIRE 3 682 (2925 4375)(3350 4375);
WIRE 3 682 (3350 4375)(3350 4500);
WIRE 16 -1 (2450 1725)(2450 1650);
WIRE 16 -1 (2450 1650)(2900 1650);
FORCEPROP 2 LAST SIG_NAME JTAG_MCP_CPU1_TDI
J 0
(2500 1660);
DISPLAY 0.617021 (2500 1660);
PAINT ORANGE (2500 1660);
WIRE 16 -1 (3425 925)(3425 750);
WIRE 16 -1 (2475 750)(3425 750);
FORCEPROP 2 LAST SIG_NAME JTAG_MCP_MUX_TDO
J 0
(2475 760);
DISPLAY 0.617021 (2475 760);
PAINT ORANGE (2475 760);
WIRE 16 -1 (3675 925)(3675 700);
WIRE 16 -1 (2475 700)(3675 700);
FORCEPROP 0 LAST SIG_NAME JTAG_MCP_TRST_N
J 0
(2475 710);
DISPLAY 0.617021 (2475 710);
PAINT ORANGE (2475 710);
WIRE 16 -1 (3175 800)(3175 925);
WIRE 16 -1 (2475 800)(3175 800);
FORCEPROP 0 LAST SIG_NAME JTAG_MCP_TMS
J 0
(2475 810);
DISPLAY 0.617021 (2475 810);
PAINT ORANGE (2475 810);
WIRE 16 -1 (2925 850)(2475 850);
FORCEPROP 2 LAST SIG_NAME JTAG_MCP_MUX_TDI
J 0
(2475 860);
DISPLAY 0.617021 (2475 860);
PAINT ORANGE (2475 860);
WIRE 16 -1 (2925 850)(2925 925);
WIRE 16 -1 (3400 4400)(2900 4400);
FORCEPROP 0 LAST SIG_NAME JTAG_MCP_TCK_R1
J 0
(2940 4410);
DISPLAY 0.617021 (2940 4410);
PAINT ORANGE (2940 4410);
FORCEPROP 2 LASTPROP $XRERR UNIQUE?
J 0
(2700 4410);
DISPLAY 0.638298 (2700 4410);
PAINT MONO (2700 4410);
DISPLAY INVISIBLE (2700 4410);
WIRE 16 -1 (-2475 2325)(-3000 2325);
FORCEPROP 0 LAST SIG_NAME JTAG_MCP_MUX_TDI
J 0
(-3010 2335);
DISPLAY 0.617021 (-3010 2335);
PAINT ORANGE (-3010 2335);
WIRE 16 -1 (-3075 4375)(-2700 4375);
FORCEPROP 2 LAST SIG_NAME JTAG_MCP_TMS
J 0
(-3075 4385);
DISPLAY 0.617021 (-3075 4385);
PAINT ORANGE (-3075 4385);
WIRE 16 -1 (-2700 4150)(-3075 4150);
FORCEPROP 0 LAST SIG_NAME PWRGD_CPU0_G
J 0
(-3075 4160);
DISPLAY 0.617021 (-3075 4160);
PAINT ORANGE (-3075 4160);
WIRE 16 -1 (-1725 3475)(-1100 3475);
FORCEPROP 0 LAST SIG_NAME JTAG_MCP_CPU0_TDO
J 0
(-1625 3485);
DISPLAY 0.617021 (-1625 3485);
PAINT ORANGE (-1625 3485);
WIRE 16 -1 (-2050 3975)(-3075 3975);
FORCEPROP 0 LAST SIG_NAME JTAG_MCP_MUX_TDI
J 0
(-3075 3985);
DISPLAY 0.617021 (-3075 3985);
PAINT ORANGE (-3075 3985);
WIRE 16 -1 (-2050 4275)(-2050 3975);
WIRE 16 -1 (-1525 4275)(-2050 4275);
WIRE 16 -1 (-2100 4325)(-1525 4325);
WIRE 16 -1 (-2100 4150)(-2100 4325);
WIRE 16 -1 (-2500 4150)(-2100 4150);
FORCEPROP 0 LAST SIG_NAME PWRGD_CPU0_G_R
J 0
(-2050 4335);
DISPLAY 0.617021 (-2050 4335);
PAINT ORANGE (-2050 4335);
FORCEPROP 2 LASTPROP $XRERR UNIQUE?
J 0
(-2290 4335);
DISPLAY 0.638298 (-2290 4335);
PAINT MONO (-2290 4335);
DISPLAY INVISIBLE (-2290 4335);
WIRE 16 -1 (-2500 4375)(-1525 4375);
FORCEPROP 2 LAST SIG_NAME JTAG_MCP_TMS_R
J 0
(-2050 4385);
DISPLAY 0.617021 (-2050 4385);
PAINT ORANGE (-2050 4385);
FORCEPROP 2 LASTPROP $XRERR UNIQUE?
J 0
(-2290 4385);
DISPLAY 0.638298 (-2290 4385);
PAINT MONO (-2290 4385);
DISPLAY INVISIBLE (-2290 4385);
WIRE 16 -1 (-3075 4425)(-1525 4425);
FORCEPROP 0 LAST SIG_NAME JTAG_MCP_MUX_TDO
J 0
(-3075 4435);
DISPLAY 0.617021 (-3075 4435);
PAINT ORANGE (-3075 4435);
WIRE 16 -1 (-1225 4325)(-600 4325);
FORCEPROP 0 LAST SIG_NAME TP_JTAG_MCP_IO8_RSVD
J 0
(-1100 4335);
DISPLAY 0.617021 (-1100 4335);
PAINT ORANGE (-1100 4335);
FORCEPROP 2 LASTPROP $XRERR UNIQUE?
J 0
(-570 4325);
DISPLAY 0.638298 (-570 4325);
PAINT MONO (-570 4325);
DISPLAY INVISIBLE (-570 4325);
WIRE 16 -1 (-600 4375)(-1225 4375);
FORCEPROP 0 LAST SIG_NAME JTAG_MCP_TRST_N
J 0
(-1100 4385);
DISPLAY 0.617021 (-1100 4385);
PAINT ORANGE (-1100 4385);
WIRE 16 -1 (-2425 3525)(-2950 3525);
FORCEPROP 0 LAST SIG_NAME JTAG_MCP_MUX_TDO
J 0
(-2960 3535);
DISPLAY 0.617021 (-2960 3535);
PAINT ORANGE (-2960 3535);
WIRE 16 -1 (-1775 2275)(-1150 2275);
FORCEPROP 0 LAST SIG_NAME JTAG_MCP_CPU0_TDI
J 0
(-1675 2285);
DISPLAY 0.617021 (-1675 2285);
PAINT ORANGE (-1675 2285);
WIRE 16 -1 (-1150 2375)(-1775 2375);
FORCEPROP 0 LAST SIG_NAME JTAG_MCP_CPU1_TDI
J 0
(-1675 2385);
DISPLAY 0.617021 (-1675 2385);
PAINT ORANGE (-1675 2385);
WIRE 16 -1 (-1750 850)(-2425 850);
FORCEPROP 0 LAST SIG_NAME JTAG_MCP_CPU0_TDO
J 0
(-2410 860);
DISPLAY 0.617021 (-2410 860);
PAINT ORANGE (-2410 860);
WIRE 16 -1 (500 1950)(1350 1950);
FORCEPROP 0 LAST SIG_NAME FM_CPU1_PKGID1
J 0
(500 1960);
DISPLAY 0.617021 (500 1960);
PAINT ORANGE (500 1960);
WIRE 16 -1 (-1750 800)(-2425 800);
FORCEPROP 0 LAST SIG_NAME FM_CPU0_AND_CPU1_MCP_PRES
J 0
(-2410 810);
DISPLAY 0.617021 (-2410 810);
PAINT ORANGE (-2410 810);
WIRE 16 -1 (-650 850)(-1250 850);
FORCEPROP 0 LAST SIG_NAME JTAG_MCP_CPU1_TDI
J 0
(-1160 860);
DISPLAY 0.617021 (-1160 860);
PAINT ORANGE (-1160 860);
WIRE 16 -1 (1400 4325)(1400 4400);
WIRE 16 -1 (1000 4400)(1400 4400);
FORCEPROP 0 LAST SIG_NAME JTAG_MCP_TRST_N
J 0
(1000 4410);
DISPLAY 0.617021 (1000 4410);
PAINT ORANGE (1000 4410);
WIRE 16 -1 (3400 4350)(2250 4350);
FORCEPROP 2 LAST SIG_NAME FM_CPU0_OR_CPU1_MCP_PRES
J 0
(2250 4360);
DISPLAY 0.617021 (2250 4360);
PAINT ORANGE (2250 4360);
WIRE 16 -1 (2600 4250)(2600 4400);
WIRE 16 -1 (2700 4400)(2600 4400);
WIRE 16 -1 (2250 4400)(2600 4400);
FORCEPROP 0 LAST SIG_NAME JTAG_MCP_TCK
J 0
(2250 4410);
DISPLAY 0.617021 (2250 4410);
PAINT ORANGE (2250 4410);
WIRE 16 -1 (500 3325)(1375 3325);
FORCEPROP 2 LAST SIG_NAME FM_CPU0_PKGID1
J 0
(500 3335);
DISPLAY 0.617021 (500 3335);
PAINT ORANGE (500 3335);
WIRE 16 -1 (2450 3025)(2875 3025);
FORCEPROP 2 LAST SIG_NAME JTAG_MCP_CPU0_TDI
J 0
(2500 3035);
DISPLAY 0.617021 (2500 3035);
PAINT ORANGE (2500 3035);
WIRE 16 -1 (2450 3025)(2450 3100);
WIRE 16 -1 (1350 2775)(500 2775);
FORCEPROP 2 LAST SIG_NAME FM_CPU0_OR_CPU1_MCP_PRES
J 0
(500 2785);
DISPLAY 0.617021 (500 2785);
PAINT ORANGE (500 2785);
WIRE 16 -1 (1700 3750)(1950 3750);
WIRE 16 -1 (1950 3375)(1875 3375);
WIRE 16 -1 (1950 3750)(1950 3375);
WIRE 16 -1 (2125 3375)(1950 3375);
FORCEPROP 0 LAST SIG_NAME JTAG_MCP_CPU0_TDI_R
J 0
(2000 3385);
DISPLAY 0.617021 (2000 3385);
PAINT ORANGE (2000 3385);
FORCEPROP 2 LASTPROP $XRERR UNIQUE?
J 0
(1760 3385);
DISPLAY 0.638298 (1760 3385);
PAINT MONO (1760 3385);
DISPLAY INVISIBLE (1760 3385);
WIRE 16 -1 (2125 3375)(2125 3300);
WIRE 16 -1 (2450 3375)(2125 3375);
WIRE 16 -1 (2450 3300)(2450 3375);
WIRE 16 -1 (2450 2825)(2450 2750);
WIRE 16 -1 (2125 2750)(2125 2825);
WIRE 16 -1 (2125 2825)(2450 2825);
WIRE 16 -1 (1850 2825)(2125 2825);
FORCEPROP 0 LAST SIG_NAME JTAG_MCP_TMS_R1
J 0
(1900 2835);
DISPLAY 0.617021 (1900 2835);
PAINT ORANGE (1900 2835);
FORCEPROP 2 LASTPROP $XRERR UNIQUE?
J 0
(1660 2835);
DISPLAY 0.638298 (1660 2835);
PAINT MONO (1660 2835);
DISPLAY INVISIBLE (1660 2835);
WIRE 16 -1 (2450 2475)(2450 2550);
WIRE 16 -1 (2450 2475)(2875 2475);
FORCEPROP 0 LAST SIG_NAME JTAG_MCP_TMS
J 0
(2500 2485);
DISPLAY 0.617021 (2500 2485);
PAINT ORANGE (2500 2485);
WIRE 16 -1 (2450 2000)(2450 1925);
WIRE 16 -1 (2150 1925)(2150 2000);
WIRE 16 -1 (2150 2000)(2450 2000);
WIRE 16 -1 (1700 2375)(1950 2375);
WIRE 16 -1 (1950 2375)(1950 2000);
WIRE 16 -1 (1950 2000)(2150 2000);
WIRE 16 -1 (1850 2000)(1950 2000);
FORCEPROP 0 LAST SIG_NAME JTAG_MCP_CPU1_TDI_R
J 0
(2025 2010);
DISPLAY 0.617021 (2025 2010);
PAINT ORANGE (2025 2010);
FORCEPROP 2 LASTPROP $XRERR UNIQUE?
J 0
(1785 2010);
DISPLAY 0.638298 (1785 2010);
PAINT MONO (1785 2010);
DISPLAY INVISIBLE (1785 2010);
DOT 1 (2125 3375);
DOT 1 (-150 1650);
DOT 1 (-1100 1450);
DOT 1 (-650 1650);
DOT 1 (-1250 2800);
DOT 1 (-1100 4800);
DOT 1 (-1150 4275);
DOT 1 (-1600 2000);
DOT 1 (-1275 2000);
DOT 1 (-1275 1575);
DOT 1 (-1550 3200);
DOT 1 (2600 4400);
DOT 1 (3425 1200);
DOT 1 (3175 1200);
DOT 1 (2125 2825);
DOT 1 (-1250 3200);
DOT 1 (1950 3375);
DOT 1 (2150 2000);
DOT 1 (1950 2000);
DOT 1 (1150 3375);
DOT 1 (1150 2000);
DOT 1 (-1100 1550);
DOT 1 (-650 1350);
DOT 1 (-650 1450);
DOT 1 (-650 1550);
DOT 1 (-150 1550);
DOT 1 (-150 1350);
DOT 1 (-150 1450);
DOT 1 (200 1650);
DOT 1 (200 1350);
DOT 1 (200 1450);
DOT 1 (200 1550);
DOT 1 (500 1550);
PAINT VIOLET (500 1550);
DOT 1 (500 1450);
DOT 1 (3575 1200);
FORCENOTE
FM_CPU1_CD_PRES_N
(-625 1575) 0;
DISPLAY LEFT (-625 1575);
DISPLAY 0.638298 (-625 1575);
PAINT PURPLE (-625 1575);
FORCENOTE
FM_CPU0_CD_PRES
(-1075 1575) 0;
DISPLAY LEFT (-1075 1575);
DISPLAY 0.638298 (-1075 1575);
PAINT PURPLE (-1075 1575);
FORCENOTE
CPU1
(250 1475) 0;
DISPLAY LEFT (250 1475);
DISPLAY 1.021277 (250 1475);
PAINT PURPLE (250 1475);
FORCENOTE
ROOM=DEBUG
(-2525 150) 0;
DISPLAY LEFT (-2525 150);
DISPLAY 1.021277 (-2525 150);
PAINT PURPLE (-2525 150);
FORCENOTE
NC7SB3157
(-100 1575) 0;
DISPLAY LEFT (-100 1575);
DISPLAY 0.638298 (-100 1575);
PAINT PURPLE (-100 1575);
FORCENOTE
JTAG
(250 1575) 0;
DISPLAY LEFT (250 1575);
DISPLAY 1.021277 (250 1575);
PAINT PURPLE (250 1575);
FORCENOTE
CPU0
(250 1375) 0;
DISPLAY LEFT (250 1375);
DISPLAY 1.021277 (250 1375);
PAINT PURPLE (250 1375);
FORCENOTE
B1
(-50 1375) 0;
DISPLAY LEFT (-50 1375);
DISPLAY 1.021277 (-50 1375);
PAINT PURPLE (-50 1375);
FORCENOTE
B0
(-50 1475) 0;
DISPLAY LEFT (-50 1475);
DISPLAY 1.021277 (-50 1475);
PAINT PURPLE (-50 1475);
FORCENOTE
MCP OR WFR PULL UPS AND PULL DOWNS
(150 4825) 0;
DISPLAY LEFT (150 4825);
DISPLAY 1.595745 (150 4825);
PAINT PURPLE (150 4825);
FORCENOTE
0
(-900 1475) 0;
DISPLAY LEFT (-900 1475);
DISPLAY 1.021277 (-900 1475);
PAINT PURPLE (-900 1475);
FORCENOTE
1
(-900 1375) 0;
DISPLAY LEFT (-900 1375);
DISPLAY 1.021277 (-900 1375);
PAINT PURPLE (-900 1375);
FORCENOTE
0
(-450 1475) 0;
DISPLAY LEFT (-450 1475);
DISPLAY 1.021277 (-450 1475);
PAINT PURPLE (-450 1475);
FORCENOTE
TP FAB4 ADD ATTRIBUTE GROUP=MCP 20170508
(3200 650) 0;
DISPLAY LEFT (3200 650);
DISPLAY 0.510638 (3200 650);
PAINT RED (3200 650);
FORCENOTE
TP FAB1 CHANGE CONNECTION 0330
(2575 4550) 0;
DISPLAY LEFT (2575 4550);
DISPLAY 0.638298 (2575 4550);
PAINT RED (2575 4550);
FORCENOTE
TP FAB1 ADD R5W1 AND R5W2 0113
(2300 4750) 0;
DISPLAY LEFT (2300 4750);
DISPLAY 1.021277 (2300 4750);
PAINT RED (2300 4750);
FORCENOTE
TP FAB1 CHANGE R4R6 AND R6M8 TO 1K OHM RES 0113
(2300 4825) 0;
DISPLAY LEFT (2300 4825);
DISPLAY 1.021277 (2300 4825);
PAINT RED (2300 4825);
FORCENOTE
C1M33, R1M22, U6M1, C6M6, U9A5, R9B10 0113
(2425 4900) 0;
DISPLAY LEFT (2425 4900);
DISPLAY 1.021277 (2425 4900);
PAINT RED (2425 4900);
FORCENOTE
TP FAB1 NOPOP U4R1, C4R2, R1M20, U1M5
(2300 4975) 0;
DISPLAY LEFT (2300 4975);
DISPLAY 1.021277 (2300 4975);
PAINT RED (2300 4975);
FORCENOTE
TP FAB4 ADD ATTRIBUTE GROUP=MCP 20170508
(2300 4675) 0;
DISPLAY LEFT (2300 4675);
DISPLAY 1.021277 (2300 4675);
PAINT RED (2300 4675);
FORCENOTE
TP FAB1 CHANGE NET NAME TO LOW ACTIVE 0216
(-775 3675) 0;
DISPLAY LEFT (-775 3675);
DISPLAY 0.638298 (-775 3675);
PAINT RED (-775 3675);
FORCENOTE
1
(-450 1375) 0;
DISPLAY LEFT (-450 1375);
DISPLAY 1.021277 (-450 1375);
PAINT PURPLE (-450 1375);
FORCENOTE
TP FAB4 ADD ATTRIBUTE GROUP=MCP 20170508
(-3675 5000) 0;
DISPLAY LEFT (-3675 5000);
DISPLAY 1.021277 (-3675 5000);
PAINT RED (-3675 5000);
QUIT
